G04 ================== begin FILE IDENTIFICATION RECORD ==================*
G04 Layout Name:  15750-1.brd*
G04 Film Name:    DRILL*
G04 File Format:  Gerber RS274X*
G04 File Origin:  Cadence Allegro 16.5-S056*
G04 Origin Date:  Fri Dec 30 13:21:30 2016*
G04 *
G04 Layer:  MANUFACTURING/NCLEGEND-1-8*
G04 Layer:  MANUFACTURING/DRILL SIZE*
G04 Layer:  DRAWING FORMAT/LAYER_PCB_STORY*
G04 Layer:  DRAWING FORMAT/LAYER_DRILL*
G04 Layer:  BOARD GEOMETRY/PANEL_OUTLINE*
G04 *
G04 Offset:    (0.00 0.00)*
G04 Mirror:    No*
G04 Mode:      Positive*
G04 Rotation:  0*
G04 FullContactRelief:  No*
G04 UndefLineWidth:     6.00*
G04 ================== end FILE IDENTIFICATION RECORD ====================*
%FSLAX35Y35*MOIN*%
%IR0*IPPOS*OFA0.00000B0.00000*MIA0B0*SFA1.00000B1.00000*%
%AMMACRO13*
1,1,.006,.005,0.0*
20,1,.006,.005,0.0,-.005,0.0,0.0*
1,1,.006,-.005,0.0*
1,1,.006,0.0,.005*
20,1,.006,0.0,.005,0.0,-.005,0.0*
1,1,.006,0.0,-.005*
1,1,.006,.0025,0.0*
20,1,.006,.0025,0.0,.0025,.005,0.0*
1,1,.006,.0025,.005*
20,1,.006,.0025,.005,.0015,.004,0.0*
1,1,.006,.0015,.004*
1,1,.006,.0015,0.0*
20,1,.006,.0015,0.0,.0035,0.0,0.0*
1,1,.006,.0035,0.0*
%
%ADD13MACRO13*%
%AMMACRO12*
1,1,.006,.006,.006*
20,1,.006,.006,.006,.006,-.006,0.0*
1,1,.006,.006,-.006*
20,1,.006,.006,-.006,-.006,-.006,0.0*
1,1,.006,-.006,-.006*
20,1,.006,-.006,-.006,-.006,.006,0.0*
1,1,.006,-.006,.006*
20,1,.006,-.006,.006,.006,.006,0.0*
1,1,.006,.006,.006*
1,1,.006,-.0019,.002*
20,1,.006,-.0019,.002,-.0013,.0026,0.0*
1,1,.006,-.0013,.0026*
20,1,.006,-.0013,.0026,-.0006,.0029,0.0*
1,1,.006,-.0006,.0029*
20,1,.006,-.0006,.0029,.0002,.003,0.0*
1,1,.006,.0002,.003*
20,1,.006,.0002,.003,.0012,.0028,0.0*
1,1,.006,.0012,.0028*
20,1,.006,.0012,.0028,.0019,.0023,0.0*
1,1,.006,.0019,.0023*
20,1,.006,.0019,.0023,.0021,.0017,0.0*
1,1,.006,.0021,.0017*
20,1,.006,.0021,.0017,.002,.0011,0.0*
1,1,.006,.002,.0011*
20,1,.006,.002,.0011,.0016,.0006,0.0*
1,1,.006,.0016,.0006*
20,1,.006,.0016,.0006,-.0004,-.0004,0.0*
1,1,.006,-.0004,-.0004*
20,1,.006,-.0004,-.0004,-.0013,-.0011,0.0*
1,1,.006,-.0013,-.0011*
20,1,.006,-.0013,-.0011,-.0019,-.0021,0.0*
1,1,.006,-.0019,-.0021*
20,1,.006,-.0019,-.0021,-.0021,-.003,0.0*
1,1,.006,-.0021,-.003*
20,1,.006,-.0021,-.003,.0021,-.003,0.0*
1,1,.006,.0021,-.003*
%
%ADD12MACRO12*%
%AMMACRO15*
1,1,.006,.009113,-.022*
20,1,.006,.009113,-.022,-.009113,-.022,0.0*
1,1,.006,-.009113,-.022*
20,1,.006,-.009113,-.022,-.022,-.009113,0.0*
1,1,.006,-.022,-.009113*
20,1,.006,-.022,-.009113,-.022,.009113,0.0*
1,1,.006,-.022,.009113*
20,1,.006,-.022,.009113,-.009113,.022,0.0*
1,1,.006,-.009113,.022*
20,1,.006,-.009113,.022,.009113,.022,0.0*
1,1,.006,.009113,.022*
20,1,.006,.009113,.022,.022,.009113,0.0*
1,1,.006,.022,.009113*
20,1,.006,.022,.009113,.022,-.009113,0.0*
1,1,.006,.022,-.009113*
20,1,.006,.022,-.009113,.009113,-.022,0.0*
1,1,.006,.009113,-.022*
1,1,.006,-.00807,-.0077*
20,1,.006,-.00807,-.0077,-.00587,-.00953,0.0*
1,1,.006,-.00587,-.00953*
20,1,.006,-.00587,-.00953,-.0033,-.01063,0.0*
1,1,.006,-.0033,-.01063*
20,1,.006,-.0033,-.01063,0.0,-.011,0.0*
1,1,.006,0.0,-.011*
20,1,.006,0.0,-.011,.0033,-.01027,0.0*
1,1,.006,.0033,-.01027*
20,1,.006,.0033,-.01027,.00587,-.0088,0.0*
1,1,.006,.00587,-.0088*
20,1,.006,.00587,-.0088,.0077,-.00623,0.0*
1,1,.006,.0077,-.00623*
20,1,.006,.0077,-.00623,.00807,-.0033,0.0*
1,1,.006,.00807,-.0033*
20,1,.006,.00807,-.0033,.00733,-.00037,0.0*
1,1,.006,.00733,-.00037*
20,1,.006,.00733,-.00037,.0055,.00147,0.0*
1,1,.006,.0055,.00147*
20,1,.006,.0055,.00147,.00293,.00293,0.0*
1,1,.006,.00293,.00293*
20,1,.006,.00293,.00293,.00037,.0033,0.0*
1,1,.006,.00037,.0033*
20,1,.006,.00037,.0033,-.0022,.00293,0.0*
1,1,.006,-.0022,.00293*
20,1,.006,-.0022,.00293,-.0055,.00147,0.0*
1,1,.006,-.0055,.00147*
20,1,.006,-.0055,.00147,-.0044,.011,0.0*
1,1,.006,-.0044,.011*
20,1,.006,-.0044,.011,.0055,.011,0.0*
1,1,.006,.0055,.011*
%
%ADD15MACRO15*%
%AMMACRO14*
1,1,.006,.0315,0.0*
20,1,.006,.0315,0.0,0.0,-.0315,0.0*
1,1,.006,0.0,-.0315*
20,1,.006,0.0,-.0315,-.0315,0.0,0.0*
1,1,.006,-.0315,0.0*
20,1,.006,-.0315,0.0,0.0,.0315,0.0*
1,1,.006,0.0,.0315*
20,1,.006,0.0,.0315,.0315,0.0,0.0*
1,1,.006,.0315,0.0*
1,1,.006,-.00998,-.00263*
20,1,.006,-.00998,-.00263,-.0063,.00105,0.0*
1,1,.006,-.0063,.00105*
20,1,.006,-.0063,.00105,-.00315,.00315,0.0*
1,1,.006,-.00315,.00315*
20,1,.006,-.00315,.00315,.00105,.0042,0.0*
1,1,.006,.00105,.0042*
20,1,.006,.00105,.0042,.00473,.00315,0.0*
1,1,.006,.00473,.00315*
20,1,.006,.00473,.00315,.00735,.00105,0.0*
1,1,.006,.00735,.00105*
20,1,.006,.00735,.00105,.00945,-.0021,0.0*
1,1,.006,.00945,-.0021*
20,1,.006,.00945,-.0021,.00998,-.00578,0.0*
1,1,.006,.00998,-.00578*
20,1,.006,.00998,-.00578,.00945,-.00893,0.0*
1,1,.006,.00945,-.00893*
20,1,.006,.00945,-.00893,.00735,-.01208,0.0*
1,1,.006,.00735,-.01208*
20,1,.006,.00735,-.01208,.0042,-.0147,0.0*
1,1,.006,.0042,-.0147*
20,1,.006,.0042,-.0147,.00053,-.01575,0.0*
1,1,.006,.00053,-.01575*
20,1,.006,.00053,-.01575,-.00367,-.0147,0.0*
1,1,.006,-.00367,-.0147*
20,1,.006,-.00367,-.0147,-.00735,-.01155,0.0*
1,1,.006,-.00735,-.01155*
20,1,.006,-.00735,-.01155,-.00945,-.00682,0.0*
1,1,.006,-.00945,-.00682*
20,1,.006,-.00945,-.00682,-.00998,-.00158,0.0*
1,1,.006,-.00998,-.00158*
20,1,.006,-.00998,-.00158,-.00893,.00525,0.0*
1,1,.006,-.00893,.00525*
20,1,.006,-.00893,.00525,-.00735,.00893,0.0*
1,1,.006,-.00735,.00893*
20,1,.006,-.00735,.00893,-.00473,.0126,0.0*
1,1,.006,-.00473,.0126*
20,1,.006,-.00473,.0126,-.00105,.01523,0.0*
1,1,.006,-.00105,.01523*
20,1,.006,-.00105,.01523,.00262,.01575,0.0*
1,1,.006,.00262,.01575*
20,1,.006,.00262,.01575,.0063,.0147,0.0*
1,1,.006,.0063,.0147*
20,1,.006,.0063,.0147,.00893,.01207,0.0*
1,1,.006,.00893,.01207*
%
%ADD14MACRO14*%
%AMMACRO11*
1,1,.006,0.0,.07*
20,1,.006,0.0,.07,-.060622,.035,0.0*
1,1,.006,-.060622,.035*
20,1,.006,-.060622,.035,-.060622,-.035,0.0*
1,1,.006,-.060622,-.035*
20,1,.006,-.060622,-.035,0.0,-.07,0.0*
1,1,.006,0.0,-.07*
20,1,.006,0.0,-.07,.060622,-.035,0.0*
1,1,.006,.060622,-.035*
20,1,.006,.060622,-.035,.060622,.035,0.0*
1,1,.006,.060622,.035*
20,1,.006,.060622,.035,0.0,.07,0.0*
1,1,.006,0.0,.07*
1,1,.006,.014,-.035*
20,1,.006,.014,-.035,.014,.035,0.0*
1,1,.006,.014,.035*
20,1,.006,.014,.035,-.02917,-.01517,0.0*
1,1,.006,-.02917,-.01517*
20,1,.006,-.02917,-.01517,.02917,-.01517,0.0*
1,1,.006,.02917,-.01517*
%
%ADD11MACRO11*%
%AMMACRO16*
1,1,.006,.02,0.0*
20,1,.006,.02,0.0,.01,.017321,0.0*
1,1,.006,.01,.017321*
20,1,.006,.01,.017321,-.01,.017321,0.0*
1,1,.006,-.01,.017321*
20,1,.006,-.01,.017321,-.02,0.0,0.0*
1,1,.006,-.02,0.0*
20,1,.006,-.02,0.0,-.01,-.017321,0.0*
1,1,.006,-.01,-.017321*
20,1,.006,-.01,-.017321,.01,-.017321,0.0*
1,1,.006,.01,-.017321*
20,1,.006,.01,-.017321,.02,0.0,0.0*
1,1,.006,.02,0.0*
1,1,.006,-.00733,-.006*
20,1,.006,-.00733,-.006,-.00533,-.00833,0.0*
1,1,.006,-.00533,-.00833*
20,1,.006,-.00533,-.00833,-.00267,-.00967,0.0*
1,1,.006,-.00267,-.00967*
20,1,.006,-.00267,-.00967,.00033,-.01,0.0*
1,1,.006,.00033,-.01*
20,1,.006,.00033,-.01,.003,-.00967,0.0*
1,1,.006,.003,-.00967*
20,1,.006,.003,-.00967,.00567,-.008,0.0*
1,1,.006,.00567,-.008*
20,1,.006,.00567,-.008,.00733,-.006,0.0*
1,1,.006,.00733,-.006*
20,1,.006,.00733,-.006,.00767,-.004,0.0*
1,1,.006,.00767,-.004*
20,1,.006,.00767,-.004,.007,-.00167,0.0*
1,1,.006,.007,-.00167*
20,1,.006,.007,-.00167,.00467,0.0,0.0*
1,1,.006,.00467,0.0*
20,1,.006,.00467,0.0,.00233,.00067,0.0*
1,1,.006,.00233,.00067*
20,1,.006,.00233,.00067,-.00067,.00067,0.0*
1,1,.006,-.00067,.00067*
1,1,.006,.00233,.00067*
20,1,.006,.00233,.00067,.00433,.00167,0.0*
1,1,.006,.00433,.00167*
20,1,.006,.00433,.00167,.006,.00333,0.0*
1,1,.006,.006,.00333*
20,1,.006,.006,.00333,.00667,.00533,0.0*
1,1,.006,.00667,.00533*
20,1,.006,.00667,.00533,.006,.00733,0.0*
1,1,.006,.006,.00733*
20,1,.006,.006,.00733,.00433,.009,0.0*
1,1,.006,.00433,.009*
20,1,.006,.00433,.009,.00133,.01,0.0*
1,1,.006,.00133,.01*
20,1,.006,.00133,.01,-.00167,.00967,0.0*
1,1,.006,-.00167,.00967*
20,1,.006,-.00167,.00967,-.00467,.00833,0.0*
1,1,.006,-.00467,.00833*
%
%ADD16MACRO16*%
%AMMACRO17*
1,1,.006,0.0,.0325*
20,1,.006,0.0,.0325,.0325,-.0325,0.0*
1,1,.006,.0325,-.0325*
20,1,.006,.0325,-.0325,-.0325,-.0325,0.0*
1,1,.006,-.0325,-.0325*
20,1,.006,-.0325,-.0325,0.0,.0325,0.0*
1,1,.006,0.0,.0325*
1,1,.006,-.00108,-.01625*
20,1,.006,-.00108,-.01625,0.0,-.00921,0.0*
1,1,.006,0.0,-.00921*
20,1,.006,0.0,-.00921,.00163,-.00325,0.0*
1,1,.006,.00163,-.00325*
20,1,.006,.00163,-.00325,.00379,.00217,0.0*
1,1,.006,.00379,.00217*
20,1,.006,.00379,.00217,.0065,.00812,0.0*
1,1,.006,.0065,.00812*
20,1,.006,.0065,.00812,.01083,.01625,0.0*
1,1,.006,.01083,.01625*
20,1,.006,.01083,.01625,-.01083,.01625,0.0*
1,1,.006,-.01083,.01625*
%
%ADD17MACRO17*%
%AMMACRO10*
1,1,.006,-.01075,.03225*
20,1,.006,-.01075,.03225,.01075,.03225,0.0*
1,1,.006,.01075,.03225*
20,1,.006,.01075,.03225,.01635,.03176,0.0*
1,1,.006,.01635,.03176*
20,1,.006,.01635,.03176,.02178,.030305,0.0*
1,1,.006,.02178,.030305*
20,1,.006,.02178,.030305,.026875,.027929,0.0*
1,1,.006,.026875,.027929*
20,1,.006,.026875,.027929,.03148,.024705,0.0*
1,1,.006,.03148,.024705*
20,1,.006,.03148,.024705,.035455,.02073,0.0*
1,1,.006,.035455,.02073*
20,1,.006,.035455,.02073,.038679,.016125,0.0*
1,1,.006,.038679,.016125*
20,1,.006,.038679,.016125,.041055,.01103,0.0*
1,1,.006,.041055,.01103*
20,1,.006,.041055,.01103,.04251,.0056,0.0*
1,1,.006,.04251,.0056*
20,1,.006,.04251,.0056,.043,0.0,0.0*
1,1,.006,.043,0.0*
20,1,.006,.043,0.0,.04251,-.0056,0.0*
1,1,.006,.04251,-.0056*
20,1,.006,.04251,-.0056,.041055,-.01103,0.0*
1,1,.006,.041055,-.01103*
20,1,.006,.041055,-.01103,.038679,-.016125,0.0*
1,1,.006,.038679,-.016125*
20,1,.006,.038679,-.016125,.035455,-.02073,0.0*
1,1,.006,.035455,-.02073*
20,1,.006,.035455,-.02073,.03148,-.024705,0.0*
1,1,.006,.03148,-.024705*
20,1,.006,.03148,-.024705,.026875,-.027929,0.0*
1,1,.006,.026875,-.027929*
20,1,.006,.026875,-.027929,.02178,-.030305,0.0*
1,1,.006,.02178,-.030305*
20,1,.006,.02178,-.030305,.01635,-.03176,0.0*
1,1,.006,.01635,-.03176*
20,1,.006,.01635,-.03176,.01075,-.03225,0.0*
1,1,.006,.01075,-.03225*
20,1,.006,.01075,-.03225,-.01075,-.03225,0.0*
1,1,.006,-.01075,-.03225*
20,1,.006,-.01075,-.03225,-.01635,-.03176,0.0*
1,1,.006,-.01635,-.03176*
20,1,.006,-.01635,-.03176,-.02178,-.030305,0.0*
1,1,.006,-.02178,-.030305*
20,1,.006,-.02178,-.030305,-.026875,-.027929,0.0*
1,1,.006,-.026875,-.027929*
20,1,.006,-.026875,-.027929,-.03148,-.024705,0.0*
1,1,.006,-.03148,-.024705*
20,1,.006,-.03148,-.024705,-.035455,-.02073,0.0*
1,1,.006,-.035455,-.02073*
20,1,.006,-.035455,-.02073,-.038679,-.016125,0.0*
1,1,.006,-.038679,-.016125*
20,1,.006,-.038679,-.016125,-.041055,-.01103,0.0*
1,1,.006,-.041055,-.01103*
20,1,.006,-.041055,-.01103,-.04251,-.0056,0.0*
1,1,.006,-.04251,-.0056*
20,1,.006,-.04251,-.0056,-.043,0.0,0.0*
1,1,.006,-.043,0.0*
20,1,.006,-.043,0.0,-.04251,.0056,0.0*
1,1,.006,-.04251,.0056*
20,1,.006,-.04251,.0056,-.041055,.01103,0.0*
1,1,.006,-.041055,.01103*
20,1,.006,-.041055,.01103,-.038679,.016125,0.0*
1,1,.006,-.038679,.016125*
20,1,.006,-.038679,.016125,-.035455,.02073,0.0*
1,1,.006,-.035455,.02073*
20,1,.006,-.035455,.02073,-.03148,.024705,0.0*
1,1,.006,-.03148,.024705*
20,1,.006,-.03148,.024705,-.026875,.027929,0.0*
1,1,.006,-.026875,.027929*
20,1,.006,-.026875,.027929,-.02178,.030305,0.0*
1,1,.006,-.02178,.030305*
20,1,.006,-.02178,.030305,-.01635,.03176,0.0*
1,1,.006,-.01635,.03176*
20,1,.006,-.01635,.03176,-.01075,.03225,0.0*
1,1,.006,-.01075,.03225*
1,1,.006,0.0,-.01612*
20,1,.006,0.0,-.01612,.00377,-.01558,0.0*
1,1,.006,.00377,-.01558*
20,1,.006,.00377,-.01558,.00807,-.01397,0.0*
1,1,.006,.00807,-.01397*
20,1,.006,.00807,-.01397,.01076,-.01128,0.0*
1,1,.006,.01076,-.01128*
20,1,.006,.01076,-.01128,.01183,-.00752,0.0*
1,1,.006,.01183,-.00752*
20,1,.006,.01183,-.00752,.01076,-.00376,0.0*
1,1,.006,.01076,-.00376*
20,1,.006,.01076,-.00376,.00753,-.00053,0.0*
1,1,.006,.00753,-.00053*
20,1,.006,.00753,-.00053,.00269,.00108,0.0*
1,1,.006,.00269,.00108*
20,1,.006,.00269,.00108,-.00268,.00108,0.0*
1,1,.006,-.00268,.00108*
20,1,.006,-.00268,.00108,-.00591,.00216,0.0*
1,1,.006,-.00591,.00216*
20,1,.006,-.00591,.00216,-.0086,.00484,0.0*
1,1,.006,-.0086,.00484*
20,1,.006,-.0086,.00484,-.00967,.0086,0.0*
1,1,.006,-.00967,.0086*
20,1,.006,-.00967,.0086,-.00806,.01237,0.0*
1,1,.006,-.00806,.01237*
20,1,.006,-.00806,.01237,-.0043,.01506,0.0*
1,1,.006,-.0043,.01506*
20,1,.006,-.0043,.01506,0.0,.01613,0.0*
1,1,.006,0.0,.01613*
20,1,.006,0.0,.01613,.0043,.01506,0.0*
1,1,.006,.0043,.01506*
20,1,.006,.0043,.01506,.00807,.01237,0.0*
1,1,.006,.00807,.01237*
20,1,.006,.00807,.01237,.00968,.0086,0.0*
1,1,.006,.00968,.0086*
20,1,.006,.00968,.0086,.0086,.00484,0.0*
1,1,.006,.0086,.00484*
20,1,.006,.0086,.00484,.00592,.00216,0.0*
1,1,.006,.00592,.00216*
20,1,.006,.00592,.00216,.00269,.00108,0.0*
1,1,.006,.00269,.00108*
20,1,.006,.00269,.00108,-.00268,.00108,0.0*
1,1,.006,-.00268,.00108*
20,1,.006,-.00268,.00108,-.00752,-.00053,0.0*
1,1,.006,-.00752,-.00053*
20,1,.006,-.00752,-.00053,-.01075,-.00376,0.0*
1,1,.006,-.01075,-.00376*
20,1,.006,-.01075,-.00376,-.01182,-.00752,0.0*
1,1,.006,-.01182,-.00752*
20,1,.006,-.01182,-.00752,-.01075,-.01128,0.0*
1,1,.006,-.01075,-.01128*
20,1,.006,-.01075,-.01128,-.00806,-.01397,0.0*
1,1,.006,-.00806,-.01397*
20,1,.006,-.00806,-.01397,-.00376,-.01558,0.0*
1,1,.006,-.00376,-.01558*
20,1,.006,-.00376,-.01558,0.0,-.01612,0.0*
1,1,.006,0.0,-.01612*
%
%ADD10MACRO10*%
%ADD18C,.02*%
%ADD19C,.006*%
G75*
%LPD*%
G75*
G54D10*
X26087Y-114844D03*
X26435Y373984D03*
X175335Y62719D03*
Y189062D03*
X547104Y69007D03*
Y195351D03*
X696192Y373984D03*
X827450Y70050D03*
G54D11*
X25596Y316176D03*
X237013Y17712D03*
X287407Y345704D03*
X827450Y182450D03*
G54D12*
X10000Y330000D03*
Y345000D03*
Y360000D03*
X40000Y270000D03*
Y285000D03*
Y300000D03*
Y330000D03*
Y345000D03*
X25000Y360000D03*
X40000D03*
X55000Y270000D03*
Y285000D03*
X52500Y325189D03*
Y331189D03*
X55000Y360000D03*
X70000Y270000D03*
X59500Y294189D03*
X72000Y286000D03*
Y290000D03*
X58000Y310689D03*
X64500Y309589D03*
X59500Y299939D03*
X71500Y315689D03*
X67900D03*
X72000Y336689D03*
X70000Y360000D03*
X85000Y270000D03*
X89000Y295189D03*
Y291189D03*
Y287189D03*
Y283189D03*
Y303689D03*
Y299689D03*
X75100Y315689D03*
X79000Y344000D03*
X89000Y329189D03*
Y333189D03*
X79000Y348000D03*
X85000Y360000D03*
X100000Y270000D03*
Y360000D03*
X115000D03*
X138500Y299500D03*
X134500Y307500D03*
X138500Y303500D03*
Y307500D03*
X137500Y324500D03*
X138000Y341500D03*
X130000Y360000D03*
X138000Y345500D03*
X142500Y299500D03*
Y303500D03*
Y307500D03*
X146500Y303500D03*
X150500D03*
X146500Y307500D03*
X150500D03*
X155000Y301350D03*
X141811Y324500D03*
X145811D03*
X153811D03*
X149811D03*
Y341500D03*
X141811D03*
X145811D03*
X153811D03*
X145000Y360000D03*
X149811Y345500D03*
X141811D03*
X145811D03*
X153811D03*
X162311Y293000D03*
X164811Y304000D03*
X160811Y310000D03*
X169811Y309500D03*
X172311Y305500D03*
X157811Y324500D03*
X161811D03*
X169811D03*
X165811D03*
X169811Y313500D03*
X165811Y341500D03*
X157811D03*
X161811D03*
X169811D03*
X160000Y360000D03*
X165811Y345500D03*
X169811D03*
X157811D03*
X161811D03*
X176311Y294000D03*
X185811Y304200D03*
Y310500D03*
X181811D03*
X181061Y297750D03*
X176168Y305500D03*
X181811Y318500D03*
X185811Y314500D03*
Y326500D03*
Y322500D03*
Y318500D03*
X181811Y326500D03*
Y322500D03*
Y314500D03*
X184500Y334000D03*
Y338000D03*
X175000Y360000D03*
X189811Y310500D03*
X195811Y296000D03*
X200811Y308000D03*
Y311000D03*
X189811Y318500D03*
Y322500D03*
Y326500D03*
Y314500D03*
X200811Y317000D03*
Y314000D03*
X190000Y360000D03*
X205000D03*
X218000Y292000D03*
X215811Y300000D03*
X222311Y325000D03*
X218311D03*
X220000Y360000D03*
X225000Y35000D03*
Y50000D03*
Y80000D03*
Y65000D03*
X230000Y75000D03*
Y67000D03*
Y71000D03*
X225000Y95000D03*
X230000Y96500D03*
X225000Y110000D03*
X230000Y126000D03*
Y130000D03*
Y122000D03*
Y138500D03*
Y142500D03*
Y134500D03*
Y175500D03*
Y179500D03*
Y183500D03*
X225000Y205000D03*
X230000Y243000D03*
Y234500D03*
Y238500D03*
Y230500D03*
Y247000D03*
Y251000D03*
X222911Y287089D03*
X237500Y340000D03*
Y344000D03*
Y336000D03*
X235000Y360000D03*
X255000Y5000D03*
Y35000D03*
X247000Y68838D03*
Y72838D03*
X251000Y68838D03*
Y72838D03*
X247000Y123838D03*
X251000D03*
X247000Y127838D03*
X251000D03*
X247000Y136338D03*
Y140838D03*
X251000D03*
Y136338D03*
Y177500D03*
X247000D03*
X251000Y181500D03*
X247000D03*
X251000Y245000D03*
X247000D03*
X251000Y236500D03*
X247000D03*
X251000Y232500D03*
X247000D03*
X251000Y249500D03*
X247000D03*
X249000Y260000D03*
X242500Y294000D03*
X246500D03*
X250500D03*
X242500Y306000D03*
Y302000D03*
Y298000D03*
X246500Y306000D03*
Y302000D03*
Y298000D03*
X250500D03*
Y302000D03*
Y306000D03*
X241500Y336000D03*
Y344000D03*
Y340000D03*
X250000Y360000D03*
X270000Y5000D03*
Y35000D03*
X262920Y131653D03*
X265000Y270000D03*
Y285000D03*
X271500Y294000D03*
X267500D03*
X271500Y306000D03*
Y302000D03*
Y298000D03*
X267500D03*
Y302000D03*
Y306000D03*
X260500Y340000D03*
Y344000D03*
Y336000D03*
X256500D03*
Y344000D03*
Y340000D03*
X265000Y360000D03*
X282500Y5000D03*
X272500Y20000D03*
X285000Y32500D03*
X275500Y63346D03*
X280000Y71614D03*
Y67677D03*
X273000Y92283D03*
X280169Y126732D03*
Y120826D03*
X275768Y144842D03*
X280169Y138543D03*
Y132637D03*
X280000Y176339D03*
X275500Y172008D03*
X280000Y180276D03*
X280169Y247205D03*
X275768Y253504D03*
X280000Y270000D03*
X275500Y294000D03*
X280000Y285000D03*
X275500Y298000D03*
Y302000D03*
Y306000D03*
X280000Y300000D03*
Y315000D03*
X295000Y5000D03*
X300000Y20000D03*
X299500Y46000D03*
X303500D03*
X300000Y35000D03*
X296500Y61000D03*
X300500D03*
X301500Y49000D03*
X297500D03*
X295500Y52000D03*
X299500D03*
X304565Y61142D03*
Y96142D03*
X304500Y92000D03*
X291500Y97204D03*
X291550Y91299D03*
X291500Y85393D03*
X295500Y110000D03*
Y100000D03*
X291500Y109960D03*
Y101960D03*
X295311Y127600D03*
X304500Y123820D03*
X291500Y114921D03*
X304565Y141142D03*
X295500Y208461D03*
X291500Y210961D03*
Y205866D03*
Y218461D03*
Y223583D03*
X301711Y245000D03*
X291500Y241299D03*
Y229488D03*
Y235394D03*
X295000Y270000D03*
Y285000D03*
Y300000D03*
Y315000D03*
X315000Y5000D03*
Y20000D03*
Y40000D03*
X313000Y179500D03*
X310000Y225000D03*
Y240000D03*
Y255000D03*
Y270000D03*
Y285000D03*
Y300000D03*
Y315000D03*
Y330000D03*
Y360000D03*
Y345000D03*
X324302Y203977D03*
X325000Y225000D03*
Y240000D03*
Y255000D03*
Y270000D03*
Y285000D03*
Y300000D03*
Y315000D03*
Y330000D03*
Y360000D03*
Y345000D03*
X345000Y5000D03*
Y20000D03*
X340000Y285000D03*
Y300000D03*
Y315000D03*
Y330000D03*
Y360000D03*
Y345000D03*
X827450Y238650D03*
G54D13*
X103000Y277500D03*
X95000D03*
X99000D03*
X106500D03*
X92500Y295000D03*
X106137Y286000D03*
X100000Y288500D03*
X92500Y298500D03*
Y309000D03*
X107000Y311500D03*
Y308000D03*
X96750Y313250D03*
X103750Y313200D03*
X100250D03*
X103500Y317000D03*
Y321000D03*
X91500Y312500D03*
X100500Y335689D03*
X96750Y328500D03*
X100500Y347289D03*
X121500Y276500D03*
X118000D03*
X114500D03*
X110500Y277500D03*
X121456Y289154D03*
X122100Y280750D03*
X112500Y289000D03*
X108000Y295000D03*
X122000Y301000D03*
X108000Y298500D03*
X115000Y305000D03*
X119000D03*
X108000Y303100D03*
X120120Y315000D03*
X116500D03*
X109500Y334500D03*
X113000D03*
X117000D03*
X121000D03*
X125000Y277000D03*
X128500Y282500D03*
X126000Y287000D03*
X130000Y298500D03*
X124000Y315000D03*
X140500Y281000D03*
X215064Y316100D03*
X236805Y146452D03*
X225000Y160250D03*
Y149250D03*
X237000Y156000D03*
Y159780D03*
Y152500D03*
X225000Y164250D03*
X236500Y168500D03*
X225000Y169500D03*
X237000Y164250D03*
X251000Y88500D03*
X252000Y151500D03*
Y155000D03*
Y160500D03*
X251500Y164500D03*
X251000Y197000D03*
X263000Y96500D03*
Y88500D03*
Y81338D03*
Y84838D03*
X269650Y97899D03*
X271650Y109710D03*
X269650Y102299D03*
X263000Y104000D03*
X262819Y100157D03*
X271650Y114110D03*
X271250Y138750D03*
X267700Y153250D03*
X268140Y161221D03*
X258750Y168000D03*
X263000Y190000D03*
Y193500D03*
X269650Y210961D03*
Y206561D03*
X263000Y205000D03*
Y197000D03*
Y212500D03*
X262819Y208819D03*
X271650Y222772D03*
Y218372D03*
X263000Y240315D03*
X275100Y109710D03*
X273100Y102299D03*
Y97899D03*
X275100Y114110D03*
X278860Y162250D03*
X279000Y166000D03*
X273500Y194055D03*
Y199961D03*
X273100Y210961D03*
Y206561D03*
X275100Y222772D03*
Y218372D03*
X273600Y240250D03*
X295000Y86699D03*
Y89899D03*
X300500Y129100D03*
X301000Y125000D03*
X292000Y126000D03*
X299300Y137043D03*
Y132643D03*
X302800Y137043D03*
Y132643D03*
X290500Y154250D03*
X296500Y157500D03*
X302000D03*
X290500Y150750D03*
X291000Y169500D03*
X292000Y181500D03*
X294750Y195261D03*
X291300Y195361D03*
X294750Y198661D03*
X291300Y198561D03*
X325244Y49902D03*
Y53051D03*
Y56201D03*
Y62500D03*
Y59351D03*
Y75099D03*
Y65650D03*
Y78248D03*
Y68799D03*
Y71949D03*
Y93996D03*
Y84548D03*
Y97146D03*
Y87697D03*
Y90847D03*
Y81398D03*
Y112894D03*
Y103445D03*
Y106595D03*
Y109744D03*
Y100296D03*
Y128642D03*
Y119193D03*
Y144390D03*
Y138091D03*
Y153839D03*
Y156988D03*
Y160138D03*
Y150689D03*
Y147540D03*
Y163288D03*
Y166437D03*
Y169587D03*
X827450Y266750D03*
G54D14*
X265551Y64724D03*
Y173386D03*
X311614Y31870D03*
X827450Y126250D03*
G54D15*
X265551Y143464D03*
Y252126D03*
X827450Y154350D03*
G54D16*
X302000Y290500D03*
Y300500D03*
Y310500D03*
X827450Y210550D03*
G54D17*
X311614Y185414D03*
X827450Y98150D03*
G54D18*
G01X-176139Y-183003D02*
G02I-12000J0D01*
G01X-181289D02*
G02I-6850J0D01*
G01X-172139D02*
X-204139D01*
G01X-188139Y-199003D02*
Y-167003D01*
G01X-172139Y-199003D02*
Y-279003D01*
G01D02*
X1178561D01*
G01X-172139Y-234503D02*
X1178561D01*
G01X-172139Y-199003D02*
X1178561D01*
G01X391061D02*
Y-279003D01*
G01X528561Y-199003D02*
Y-279003D01*
G01X643561Y-199003D02*
Y-279003D01*
G01X811061Y-199003D02*
Y-279003D01*
G01X981061Y-199003D02*
Y-279003D01*
G01X1178561Y-199003D02*
Y-279003D01*
G01X1210561Y-183003D02*
X1178561D01*
G01X1206561D02*
G02I-12000J0D01*
G01X1201411D02*
G02I-6850J0D01*
G01X1194561Y-199003D02*
Y-167003D01*
G54D19*
G01X-148956Y-251503D02*
Y-269003D01*
X-140222D01*
G01X-127089Y-257337D02*
Y-269003D01*
G01Y-252670D02*
X-127526Y-252378D01*
Y-251795D01*
X-127089Y-251503D01*
X-126652Y-251795D01*
Y-252378D01*
X-127089Y-252670D01*
G01X-112646Y-273378D02*
X-111117Y-274545D01*
X-109371Y-274836D01*
X-107843Y-274545D01*
X-106532Y-273087D01*
X-105659Y-271045D01*
Y-257337D01*
G01Y-259670D02*
X-106532Y-258503D01*
X-107843Y-257628D01*
X-109371Y-257337D01*
X-111117Y-257920D01*
X-112209Y-259086D01*
X-113083Y-261128D01*
X-113519Y-263170D01*
X-113301Y-264920D01*
X-112427Y-266962D01*
X-111117Y-268420D01*
X-109371Y-269003D01*
X-108061Y-268711D01*
X-106532Y-267545D01*
X-105659Y-266379D01*
G01X-95801Y-269003D02*
Y-251503D01*
G01Y-259961D02*
X-94709Y-258503D01*
X-93617Y-257628D01*
X-91871Y-257337D01*
X-90561Y-257628D01*
X-89032Y-258795D01*
X-88377Y-260545D01*
Y-269003D01*
G01X-74589Y-251503D02*
Y-269003D01*
G01X-77646Y-257337D02*
X-71532D01*
G01X-60801Y-269003D02*
Y-257337D01*
G01Y-260253D02*
X-59927Y-258795D01*
X-58617Y-257628D01*
X-56871Y-257337D01*
X-55343Y-257628D01*
X-54032Y-258795D01*
X-53377Y-260836D01*
Y-269003D01*
G01X-39589Y-257337D02*
Y-269003D01*
G01Y-252670D02*
X-40026Y-252378D01*
Y-251795D01*
X-39589Y-251503D01*
X-39152Y-251795D01*
Y-252378D01*
X-39589Y-252670D01*
G01X-25801Y-269003D02*
Y-257337D01*
G01Y-260253D02*
X-24927Y-258795D01*
X-23617Y-257628D01*
X-21871Y-257337D01*
X-20343Y-257628D01*
X-19032Y-258795D01*
X-18377Y-260836D01*
Y-269003D01*
G01X-7646Y-273378D02*
X-6117Y-274545D01*
X-4371Y-274836D01*
X-2843Y-274545D01*
X-1532Y-273087D01*
X-659Y-271045D01*
Y-257337D01*
G01Y-259670D02*
X-1532Y-258503D01*
X-2843Y-257628D01*
X-4371Y-257337D01*
X-6117Y-257920D01*
X-7209Y-259086D01*
X-8083Y-261128D01*
X-8519Y-263170D01*
X-8301Y-264920D01*
X-7427Y-266962D01*
X-6117Y-268420D01*
X-4371Y-269003D01*
X-3061Y-268711D01*
X-1532Y-267545D01*
X-659Y-266379D01*
G01X26044Y-269003D02*
Y-251503D01*
X31284D01*
X33031Y-252378D01*
X34341Y-254420D01*
X34778Y-256753D01*
X34341Y-259086D01*
X33249Y-260836D01*
X31284Y-261712D01*
X26044D01*
G01X42452Y-251503D02*
X47911Y-269003D01*
X53370Y-251503D01*
G01X65411D02*
Y-269003D01*
G01X60389Y-251503D02*
X70433D01*
G01X94734Y-269003D02*
Y-251503D01*
X100411Y-266086D01*
X106088Y-251503D01*
Y-269003D01*
G01X117911Y-269586D02*
X117474Y-269295D01*
Y-268711D01*
X117911Y-268420D01*
X118348Y-268711D01*
Y-269295D01*
X117911Y-269586D01*
G01X131263Y-254420D02*
X132573Y-252670D01*
X134101Y-251795D01*
X135848Y-251503D01*
X138031Y-252086D01*
X139559Y-253545D01*
X139996Y-255294D01*
X139778Y-257045D01*
X138904Y-258503D01*
X134538Y-261420D01*
X132573Y-263461D01*
X131263Y-266379D01*
X130826Y-269003D01*
X139996D01*
G01X164952D02*
X170411Y-251503D01*
X175870Y-269003D01*
G01X173904Y-262878D02*
X166917D01*
G01X191841Y-251503D02*
Y-269003D01*
G01Y-266379D02*
X190968Y-267837D01*
X189657Y-268711D01*
X188129Y-269003D01*
X186383Y-268420D01*
X185073Y-266962D01*
X184199Y-265212D01*
X183981Y-263170D01*
X184199Y-261128D01*
X185073Y-259378D01*
X186383Y-257920D01*
X188129Y-257337D01*
X189657Y-257628D01*
X190749Y-258212D01*
X191841Y-259378D01*
G01X209341Y-269003D02*
Y-257337D01*
G01Y-259378D02*
X208468Y-258212D01*
X207157Y-257628D01*
X205629Y-257337D01*
X204101Y-257920D01*
X202791Y-259086D01*
X201917Y-260836D01*
X201481Y-263170D01*
X201917Y-265503D01*
X202791Y-267253D01*
X204101Y-268420D01*
X205629Y-269003D01*
X207157Y-268711D01*
X208468Y-267837D01*
X209341Y-266670D01*
G01X218981Y-274836D02*
Y-257337D01*
G01Y-259961D02*
X220073Y-258503D01*
X221164Y-257628D01*
X222911Y-257337D01*
X224439Y-257628D01*
X225968Y-259086D01*
X226623Y-261128D01*
X226841Y-263170D01*
X226623Y-265212D01*
X225968Y-267253D01*
X224657Y-268420D01*
X222911Y-269003D01*
X221383Y-268711D01*
X219854Y-267837D01*
X218981Y-266670D01*
G01X240411Y-251503D02*
Y-269003D01*
G01X237354Y-257337D02*
X243468D01*
G01X257911Y-269003D02*
X256601Y-268711D01*
X255291Y-267545D01*
X254417Y-265503D01*
X253981Y-263170D01*
X254417Y-260836D01*
X255291Y-258795D01*
X256601Y-257628D01*
X257911Y-257337D01*
X259221Y-257628D01*
X260531Y-258795D01*
X261404Y-260836D01*
X261623Y-263170D01*
X261404Y-265503D01*
X260531Y-267545D01*
X259221Y-268711D01*
X257911Y-269003D01*
G01X272354D02*
Y-257337D01*
G01Y-259670D02*
X273446Y-258503D01*
X274538Y-257628D01*
X276066Y-257337D01*
X277157Y-257628D01*
X278468Y-258503D01*
G01X315214Y-252962D02*
X313904Y-252086D01*
X312376Y-251503D01*
X310629D01*
X308664Y-252378D01*
X307136Y-253836D01*
X306044Y-255587D01*
X305171Y-258503D01*
X304952Y-261128D01*
X305389Y-263753D01*
X306044Y-265503D01*
X307354Y-267253D01*
X308883Y-268420D01*
X310411Y-269003D01*
X311939D01*
X313468Y-268420D01*
X314778Y-267545D01*
X315870Y-266379D01*
G01X331841Y-269003D02*
Y-257337D01*
G01Y-259378D02*
X330968Y-258212D01*
X329657Y-257628D01*
X328129Y-257337D01*
X326601Y-257920D01*
X325291Y-259086D01*
X324417Y-260836D01*
X323981Y-263170D01*
X324417Y-265503D01*
X325291Y-267253D01*
X326601Y-268420D01*
X328129Y-269003D01*
X329657Y-268711D01*
X330968Y-267837D01*
X331841Y-266670D01*
G01X342354Y-269003D02*
Y-257337D01*
G01Y-259670D02*
X343446Y-258503D01*
X344538Y-257628D01*
X346066Y-257337D01*
X347157Y-257628D01*
X348468Y-258503D01*
G01X366841Y-251503D02*
Y-269003D01*
G01Y-266379D02*
X365968Y-267837D01*
X364657Y-268711D01*
X363129Y-269003D01*
X361383Y-268420D01*
X360073Y-266962D01*
X359199Y-265212D01*
X358981Y-263170D01*
X359199Y-261128D01*
X360073Y-259378D01*
X361383Y-257920D01*
X363129Y-257337D01*
X364657Y-257628D01*
X365749Y-258212D01*
X366841Y-259378D01*
G01X-1Y-113228D02*
Y-117165D01*
G03X7873Y-125039I7874J0D01*
G01X714566D01*
G03X722440Y-117165I0J7874D01*
G01Y-113228D01*
G01X1968Y40473D02*
X9842D01*
G02X11811Y38504I0J-1969D01*
G01Y-16772D01*
G02X9842Y-18740I-1969J1D01*
G01X1968D01*
G03X0Y-20709I0J-1968D01*
G01Y-97480D01*
G03X7874Y-105354I7874J0D01*
G01X341535D01*
G03X349409Y-97480I0J7874D01*
G01Y-15748D01*
G03X341535Y-7874I-7874J0D01*
G01X141338D01*
G02X133464Y0I0J7874D01*
G01Y250197D01*
G03X125590Y258071I-7874J0D01*
G01X1968D01*
G03X0Y256102I0J-1968D01*
G01Y236673D01*
G03X1968Y234705I1968J0D01*
G01X28346D01*
G02X30315Y232736I0J-1969D01*
G01Y216004D01*
G02X28346Y214036I-1968J0D01*
G01X23228D01*
G03X21259Y212067I0J-1969D01*
G01Y86752D01*
G03X23228Y84784I1969J1D01*
G01X28346D01*
G02X30315Y82815I0J-1969D01*
G01Y66083D01*
G02X28346Y64114I-1969J0D01*
G01X1968D01*
G03X0Y62146I0J-1968D01*
G01Y42441D01*
G03X1968Y40473I1968J0D01*
G01X-1Y-113228D02*
X13591D01*
G01X347441Y217598D02*
X339567D01*
G02X337598Y219567I0J1969D01*
G01Y274843D01*
G02X339567Y276811I1969J-1D01*
G01X347441D01*
G03X349409Y278780I0J1968D01*
G01Y355551D01*
G03X341535Y363425I-7874J0D01*
G01X7874D01*
G03X0Y355551I0J-7874D01*
G01Y273819D01*
G03X7874Y265945I7874J0D01*
G01X208071D01*
G02X215945Y258071I0J-7874D01*
G01Y7874D01*
G03X223819Y0I7874J0D01*
G01X347441D01*
G03X349409Y1969I0J1968D01*
G01Y21398D01*
G03X347441Y23366I-1968J0D01*
G01X321063D01*
G02X319094Y25335I0J1969D01*
G01Y42067D01*
G02X321063Y44035I1969J-1D01*
G01X326181D01*
G03X328150Y46004I0J1969D01*
G01Y171319D01*
G03X326181Y173287I-1968J0D01*
G01X321063D01*
G02X319094Y175256I0J1969D01*
G01Y191988D01*
G02X321063Y193957I1969J0D01*
G01X347441D01*
G03X349409Y195925I0J1968D01*
G01Y215630D01*
G03X347441Y217598I-1968J0D01*
G01X245745Y383110D02*
X7874D01*
G03X0Y375236I0J-7874D01*
G01Y371299D01*
G01D02*
X13591D01*
G01Y-113228D02*
G03Y-105354I0J3937D01*
G01Y258071D02*
G03Y265945I0J3937D01*
G01Y363425D02*
G03Y371299I0J3937D01*
G01X38787Y-113228D02*
X237000D01*
G01X38787Y-105354D02*
G03Y-113228I1J-3937D01*
G01Y265945D02*
G03Y258071I1J-3937D01*
G01X237000Y371299D02*
X38787D01*
G01D02*
G03Y363425I1J-3937D01*
G01X68484Y-224003D02*
Y-206503D01*
X74161Y-221086D01*
X79838Y-206503D01*
Y-224003D01*
G01X91661D02*
X90351Y-223711D01*
X89041Y-222545D01*
X88167Y-220503D01*
X87731Y-218170D01*
X88167Y-215836D01*
X89041Y-213795D01*
X90351Y-212628D01*
X91661Y-212337D01*
X92971Y-212628D01*
X94281Y-213795D01*
X95154Y-215836D01*
X95373Y-218170D01*
X95154Y-220503D01*
X94281Y-222545D01*
X92971Y-223711D01*
X91661Y-224003D01*
G01X113091Y-206503D02*
Y-224003D01*
G01Y-221379D02*
X112218Y-222837D01*
X110907Y-223711D01*
X109379Y-224003D01*
X107633Y-223420D01*
X106323Y-221962D01*
X105449Y-220212D01*
X105231Y-218170D01*
X105449Y-216128D01*
X106323Y-214378D01*
X107633Y-212920D01*
X109379Y-212337D01*
X110907Y-212628D01*
X111999Y-213212D01*
X113091Y-214378D01*
G01X123386Y-216128D02*
X130373D01*
X129718Y-214086D01*
X128626Y-212920D01*
X127098Y-212337D01*
X125569Y-212628D01*
X124259Y-213503D01*
X123386Y-215545D01*
X122949Y-217295D01*
Y-219045D01*
X123386Y-220795D01*
X124478Y-222545D01*
X125788Y-223711D01*
X127316Y-224003D01*
X128844Y-223420D01*
X130373Y-221670D01*
G01X144161Y-224003D02*
Y-206503D01*
G01X141338Y116437D02*
G03X133464I-3937J0D01*
G01Y141634D02*
G03X141338I3937J0D01*
G01Y0D02*
Y116437D01*
G01X162106Y0D02*
X141337D01*
G01X141338Y141634D02*
Y258071D01*
G01D02*
X162106D01*
G01Y-7874D02*
G03Y0I0J3937D01*
G01X179626Y62719D02*
G03X171044I-4291J0D01*
G03X179626I4291J0D01*
G01Y189063D02*
G03X171044Y189062I-4291J0D01*
G03X179626Y189063I4291J1D01*
G01X162106Y258071D02*
G03Y265945I0J3937D01*
G01X187302Y0D02*
G03Y-7874I1J-3937D01*
G01X208071Y0D02*
X187302D01*
G01Y265945D02*
G03Y258071I1J-3937D01*
G01D02*
X208071D01*
G01X207913Y0D02*
X208071D01*
G01Y116437D02*
Y0D01*
G01X215945Y116437D02*
G03X208071I-3937J0D01*
G01Y141634D02*
G03X215945I3937J0D01*
G01X208071Y258071D02*
Y141634D01*
G01X237000Y-113228D02*
G03Y-105354I0J3937D01*
G01Y363425D02*
G03Y371299I0J3937D01*
G01X245745Y383110D02*
G03X253619I3937J0D01*
G01X722440Y371299D02*
Y375236D01*
G03X714566Y383110I-7874J0D01*
G01X253619D01*
G01X262196Y-113228D02*
X460244D01*
G01X262196Y-105354D02*
G03Y-113228I0J-3937D01*
G01Y371299D02*
X460244D01*
G01X262196D02*
G03Y363425I0J-3937D01*
G01X310621Y-7874D02*
G03Y0I0J3937D01*
G01X335817D02*
G03Y-7874I1J-3937D01*
G01X353346Y-47481D02*
G03X349409Y-51418I0J-3937D01*
G01Y-20709D02*
G03X353346Y-24646I3937J0D01*
G01Y282717D02*
G03X349409Y278780I0J-3937D01*
G01Y309489D02*
G03X353346Y305552I3937J0D01*
G01Y-47481D02*
X369094D01*
G01X373031Y-51418D02*
G03X369094Y-47481I-3937J0D01*
G01X353346Y-24646D02*
X369094D01*
G01D02*
G03X373031Y-20709I0J3937D01*
G01X353346Y282717D02*
X369094D01*
G01X373031Y278780D02*
G03X369094Y282717I-3937J0D01*
G01X353346Y305552D02*
X369094D01*
G01D02*
G03X373031Y309489I0J3937D01*
G01X374999Y40473D02*
X382873D01*
G02X384842Y38504I0J-1969D01*
G01Y-16772D01*
G02X382873Y-18740I-1969J1D01*
G01X374999D01*
G03X373031Y-20709I0J-1968D01*
G01Y-97480D01*
G03X380905Y-105354I7874J0D01*
G01X714566D01*
G03X722440Y-97480I0J7874D01*
G01Y-15748D01*
G03X714566Y-7874I-7874J0D01*
G01X514369D01*
G02X506495Y0I0J7874D01*
G01Y250197D01*
G03X498621Y258071I-7874J0D01*
G01X374999D01*
G03X373031Y256102I0J-1968D01*
G01Y236673D01*
G03X374999Y234705I1968J0D01*
G01X401377D01*
G02X403346Y232736I0J-1969D01*
G01Y216004D01*
G02X401377Y214036I-1968J0D01*
G01X396259D01*
G03X394290Y212067I0J-1969D01*
G01Y86752D01*
G03X396259Y84784I1969J1D01*
G01X401377D01*
G02X403346Y82815I0J-1969D01*
G01Y66083D01*
G02X401377Y64114I-1969J0D01*
G01X374999D01*
G03X373031Y62146I0J-1968D01*
G01Y42441D01*
G03X374999Y40473I1968J0D01*
G01X720472Y217598D02*
X712598D01*
G02X710629Y219567I0J1969D01*
G01Y274843D01*
G02X712598Y276811I1969J-1D01*
G01X720472D01*
G03X722440Y278780I0J1968D01*
G01Y355551D01*
G03X714566Y363425I-7874J0D01*
G01X380905D01*
G03X373031Y355551I0J-7874D01*
G01Y273819D01*
G03X380905Y265945I7874J0D01*
G01X581102D01*
G02X588976Y258071I0J-7874D01*
G01Y7874D01*
G03X596850Y0I7874J0D01*
G01X720472D01*
G03X722440Y1969I0J1968D01*
G01Y21398D01*
G03X720472Y23366I-1968J0D01*
G01X694094D01*
G02X692125Y25335I0J1969D01*
G01Y42067D01*
G02X694094Y44035I1969J-1D01*
G01X699212D01*
G03X701181Y46004I0J1969D01*
G01Y171319D01*
G03X699212Y173287I-1969J-1D01*
G01X694094D01*
G02X692125Y175256I0J1969D01*
G01Y191988D01*
G02X694094Y193957I1969J0D01*
G01X720472D01*
G03X722440Y195925I0J1968D01*
G01Y215630D01*
G03X720472Y217598I-1968J0D01*
G01X386622Y258071D02*
G03Y265945I0J3937D01*
G01X424761Y-269003D02*
Y-251503D01*
X422141Y-255003D01*
G01Y-269003D02*
X427381D01*
G01X437458Y-266379D02*
X438767Y-267837D01*
X440296Y-268711D01*
X442261Y-269003D01*
X444226Y-268420D01*
X445754Y-267253D01*
X446846Y-265212D01*
X447064Y-262878D01*
X446628Y-260545D01*
X445536Y-259086D01*
X444007Y-257920D01*
X442479Y-257628D01*
X440951Y-257920D01*
X438986Y-259086D01*
X439641Y-251503D01*
X445536D01*
G01X459324Y-269003D02*
X459761Y-265212D01*
X460416Y-262003D01*
X461289Y-259086D01*
X462381Y-255878D01*
X464128Y-251503D01*
X455394D01*
G01X472458Y-266379D02*
X473767Y-267837D01*
X475296Y-268711D01*
X477261Y-269003D01*
X479226Y-268420D01*
X480754Y-267253D01*
X481846Y-265212D01*
X482064Y-262878D01*
X481628Y-260545D01*
X480536Y-259086D01*
X479007Y-257920D01*
X477479Y-257628D01*
X475951Y-257920D01*
X473986Y-259086D01*
X474641Y-251503D01*
X480536D01*
G01X494761D02*
X493014Y-252086D01*
X491704Y-253545D01*
X490831Y-255294D01*
X490176Y-257628D01*
X489958Y-260253D01*
X490176Y-262878D01*
X490831Y-265212D01*
X491704Y-266962D01*
X493014Y-268420D01*
X494761Y-269003D01*
X496507Y-268420D01*
X497818Y-266962D01*
X498691Y-265212D01*
X499346Y-262878D01*
X499564Y-260253D01*
X499346Y-257628D01*
X498691Y-255294D01*
X497818Y-253545D01*
X496507Y-252086D01*
X494761Y-251503D01*
G01X411644Y-224003D02*
Y-206503D01*
X416884D01*
X418631Y-207378D01*
X419941Y-209420D01*
X420378Y-211753D01*
X419941Y-214086D01*
X418849Y-215836D01*
X416884Y-216712D01*
X411644D01*
G01X438314Y-207962D02*
X437004Y-207086D01*
X435476Y-206503D01*
X433729D01*
X431764Y-207378D01*
X430236Y-208836D01*
X429144Y-210587D01*
X428271Y-213503D01*
X428052Y-216128D01*
X428489Y-218753D01*
X429144Y-220503D01*
X430454Y-222253D01*
X431983Y-223420D01*
X433511Y-224003D01*
X435039D01*
X436568Y-223420D01*
X437878Y-222545D01*
X438970Y-221379D01*
G01X452757Y-214670D02*
X453631Y-213795D01*
X454286Y-212337D01*
X454723Y-210294D01*
X454286Y-208545D01*
X453413Y-207378D01*
X451884Y-206503D01*
X445989D01*
Y-224003D01*
X453194D01*
X454723Y-222837D01*
X455596Y-221086D01*
X456033Y-219045D01*
X455596Y-217003D01*
X454286Y-215253D01*
X452757Y-214670D01*
X445989D01*
G01X461961Y-229836D02*
X475061D01*
G01X480989Y-224003D02*
Y-206503D01*
X491033Y-224003D01*
Y-206503D01*
G01X503511Y-224003D02*
X501764Y-223711D01*
X500236Y-222545D01*
X498926Y-220795D01*
X498052Y-218753D01*
X497616Y-216420D01*
Y-214086D01*
X498052Y-211753D01*
X498926Y-209711D01*
X500236Y-207962D01*
X501764Y-206795D01*
X503511Y-206503D01*
X505257Y-206795D01*
X506786Y-207962D01*
X508096Y-209711D01*
X508970Y-211753D01*
X509406Y-214086D01*
Y-216420D01*
X508970Y-218753D01*
X508096Y-220795D01*
X506786Y-222545D01*
X505257Y-223711D01*
X503511Y-224003D01*
G01X411819Y265945D02*
G03Y258071I0J-3937D01*
G01X460244Y-113228D02*
G03Y-105354I0J3937D01*
G01Y363425D02*
G03Y371299I0J3937D01*
G01X485441Y-105354D02*
G03Y-113228I0J-3937D01*
G01Y371299D02*
G03Y363425I0J-3937D01*
G01Y-113228D02*
X683652D01*
G01X485441Y371299D02*
X683652D01*
G01X514369Y0D02*
Y116437D01*
G01X535137Y0D02*
X514369D01*
G01Y116437D02*
G03X506494I-3937J0D01*
G01Y141634D02*
G03X514369I3937J0D01*
G01D02*
Y258071D01*
G01D02*
X535137D01*
G01Y-7874D02*
G03Y0I0J3937D01*
G01X551396Y69008D02*
G03X542813I-4291J0D01*
G03X551396I4291J0D01*
G01Y195351D02*
G03X542813Y195352I-4292J0D01*
G03X551396Y195351I4291J-1D01*
G01X535137Y258071D02*
G03Y265945I0J3937D01*
G01X554352Y-206503D02*
X559811Y-224003D01*
X565270Y-206503D01*
G01X581678Y-224003D02*
X572944D01*
Y-206503D01*
X581678D01*
G01X578184Y-214961D02*
X572944D01*
G01X590444Y-224003D02*
Y-206503D01*
X595903D01*
X597649Y-207378D01*
X598741Y-208545D01*
X599178Y-210878D01*
X598741Y-213212D01*
X597431Y-214670D01*
X595903Y-215545D01*
X590444D01*
G01X595903D02*
X599178Y-224003D01*
G01X612311Y-224586D02*
X611874Y-224295D01*
Y-223711D01*
X612311Y-223420D01*
X612748Y-223711D01*
Y-224295D01*
X612311Y-224586D01*
G01X560333Y0D02*
G03Y-7874I1J-3937D01*
G01X581102Y0D02*
X560333D01*
G01Y265945D02*
G03Y258071I1J-3937D01*
G01D02*
X581102D01*
G01X586061Y-269003D02*
Y-251503D01*
X583441Y-255003D01*
G01Y-269003D02*
X588681D01*
G01X581102Y116437D02*
Y0D01*
G01X588976Y116437D02*
G03X581102I-3937J0D01*
G01Y141634D02*
G03X588976I3937J0D01*
G01X581102Y258071D02*
Y141634D01*
G01X687458Y-269003D02*
Y-251503D01*
X691824D01*
X693571Y-252378D01*
X694881Y-253545D01*
X695973Y-255294D01*
X696846Y-257337D01*
X697064Y-260253D01*
X696846Y-263170D01*
X695973Y-265212D01*
X694881Y-266962D01*
X693571Y-268128D01*
X691824Y-269003D01*
X687458D01*
G01X705394D02*
Y-251503D01*
X710853D01*
X712599Y-252378D01*
X713691Y-253545D01*
X714128Y-255878D01*
X713691Y-258212D01*
X712381Y-259670D01*
X710853Y-260545D01*
X705394D01*
G01X710853D02*
X714128Y-269003D01*
G01X724641Y-251503D02*
X729881D01*
G01X727261D02*
Y-269003D01*
G01X724641D02*
X729881D01*
G01X740394Y-251503D02*
Y-269003D01*
X749128D01*
G01X757894Y-251503D02*
Y-269003D01*
X766628D01*
G01X687894Y-206503D02*
Y-224003D01*
X696628D01*
G01X713691D02*
Y-212337D01*
G01Y-214378D02*
X712818Y-213212D01*
X711507Y-212628D01*
X709979Y-212337D01*
X708451Y-212920D01*
X707141Y-214086D01*
X706267Y-215836D01*
X705831Y-218170D01*
X706267Y-220503D01*
X707141Y-222253D01*
X708451Y-223420D01*
X709979Y-224003D01*
X711507Y-223711D01*
X712818Y-222837D01*
X713691Y-221670D01*
G01X722676Y-229253D02*
X723986Y-229836D01*
X725733Y-229253D01*
X726824Y-228087D01*
X727698Y-226628D01*
X729007Y-221962D01*
X731846Y-212337D01*
G01X724859D02*
X729007Y-221962D01*
G01X741486Y-216128D02*
X748473D01*
X747818Y-214086D01*
X746726Y-212920D01*
X745198Y-212337D01*
X743669Y-212628D01*
X742359Y-213503D01*
X741486Y-215545D01*
X741049Y-217295D01*
Y-219045D01*
X741486Y-220795D01*
X742578Y-222545D01*
X743888Y-223711D01*
X745416Y-224003D01*
X746944Y-223420D01*
X748473Y-221670D01*
G01X759204Y-224003D02*
Y-212337D01*
G01Y-214670D02*
X760296Y-213503D01*
X761388Y-212628D01*
X762916Y-212337D01*
X764007Y-212628D01*
X765318Y-213503D01*
G01X683652Y-113228D02*
G03Y-105354I0J3937D01*
G01Y-7874D02*
G03Y0I0J3937D01*
G01Y363425D02*
G03Y371299I0J3937D01*
G01X708848Y-113228D02*
X722440D01*
G01X708848Y-105354D02*
G03Y-113228I1J-3937D01*
G01Y0D02*
G03Y-7874I1J-3937D01*
G01Y371299D02*
X722440D01*
G01X708848D02*
G03Y363425I1J-3937D01*
G01X783585Y26000D02*
Y38500D01*
X790715Y26000D01*
Y38500D01*
G01X799550Y26000D02*
X798620Y26208D01*
X797690Y27041D01*
X797070Y28500D01*
X796760Y30167D01*
X797070Y31833D01*
X797690Y33292D01*
X798620Y34125D01*
X799550Y34333D01*
X800480Y34125D01*
X801410Y33292D01*
X802030Y31833D01*
X802185Y30167D01*
X802030Y28500D01*
X801410Y27041D01*
X800480Y26208D01*
X799550Y26000D01*
G01X811950Y38500D02*
Y26000D01*
G01X809780Y34333D02*
X814120D01*
G01X822025Y31625D02*
X826985D01*
X826520Y33083D01*
X825745Y33917D01*
X824660Y34333D01*
X823575Y34125D01*
X822645Y33500D01*
X822025Y32042D01*
X821715Y30791D01*
Y29542D01*
X822025Y28292D01*
X822800Y27041D01*
X823730Y26208D01*
X824815Y26000D01*
X825900Y26417D01*
X826985Y27666D01*
G01X836750Y25583D02*
X836440Y25792D01*
Y26208D01*
X836750Y26417D01*
X837060Y26208D01*
Y25792D01*
X836750Y25583D01*
G01Y31208D02*
X836440Y31417D01*
Y31833D01*
X836750Y32042D01*
X837060Y31833D01*
Y31417D01*
X836750Y31208D01*
G01X846050Y26000D02*
Y38500D01*
X849925D01*
X851165Y37875D01*
X851940Y37042D01*
X852250Y35375D01*
X851940Y33708D01*
X851010Y32667D01*
X849925Y32042D01*
X846050D01*
G01X849925D02*
X852250Y26000D01*
G01X859225Y31625D02*
X864185D01*
X863720Y33083D01*
X862945Y33917D01*
X861860Y34333D01*
X860775Y34125D01*
X859845Y33500D01*
X859225Y32042D01*
X858915Y30791D01*
Y29542D01*
X859225Y28292D01*
X860000Y27041D01*
X860930Y26208D01*
X862015Y26000D01*
X863100Y26417D01*
X864185Y27666D01*
G01X873020Y26000D02*
Y36625D01*
X873330Y37666D01*
X873950Y38292D01*
X874880Y38500D01*
X875810Y38083D01*
X876275Y37042D01*
G01X874415Y33500D02*
X871315D01*
G01X884025Y31625D02*
X888985D01*
X888520Y33083D01*
X887745Y33917D01*
X886660Y34333D01*
X885575Y34125D01*
X884645Y33500D01*
X884025Y32042D01*
X883715Y30791D01*
Y29542D01*
X884025Y28292D01*
X884800Y27041D01*
X885730Y26208D01*
X886815Y26000D01*
X887900Y26417D01*
X888985Y27666D01*
G01X896580Y26000D02*
Y34333D01*
G01Y32667D02*
X897355Y33500D01*
X898130Y34125D01*
X899215Y34333D01*
X899990Y34125D01*
X900920Y33500D01*
G01X923550Y38500D02*
Y26000D01*
G01X921380Y34333D02*
X925720D01*
G01X935950Y26000D02*
X935020Y26208D01*
X934090Y27041D01*
X933470Y28500D01*
X933160Y30167D01*
X933470Y31833D01*
X934090Y33292D01*
X935020Y34125D01*
X935950Y34333D01*
X936880Y34125D01*
X937810Y33292D01*
X938430Y31833D01*
X938585Y30167D01*
X938430Y28500D01*
X937810Y27041D01*
X936880Y26208D01*
X935950Y26000D01*
G01X957340D02*
Y38500D01*
X960440D01*
X961680Y37875D01*
X962610Y37042D01*
X963385Y35792D01*
X964005Y34333D01*
X964160Y32250D01*
X964005Y30167D01*
X963385Y28708D01*
X962610Y27458D01*
X961680Y26625D01*
X960440Y26000D01*
X957340D01*
G01X970050D02*
Y38500D01*
X973925D01*
X975165Y37875D01*
X975940Y37042D01*
X976250Y35375D01*
X975940Y33708D01*
X975010Y32667D01*
X973925Y32042D01*
X970050D01*
G01X973925D02*
X976250Y26000D01*
G01X983690Y38500D02*
X987410D01*
G01X985550D02*
Y26000D01*
G01X983690D02*
X987410D01*
G01X994850Y38500D02*
Y26000D01*
X1001050D01*
G01X1007250Y38500D02*
Y26000D01*
X1013450D01*
G01X1035150D02*
Y38500D01*
G01X1050340Y26000D02*
Y34333D01*
G01Y32875D02*
X1049720Y33708D01*
X1048790Y34125D01*
X1047705Y34333D01*
X1046620Y33917D01*
X1045690Y33083D01*
X1045070Y31833D01*
X1044760Y30167D01*
X1045070Y28500D01*
X1045690Y27250D01*
X1046620Y26417D01*
X1047705Y26000D01*
X1048790Y26208D01*
X1049720Y26833D01*
X1050340Y27666D01*
G01X1056695Y22250D02*
X1057625Y21833D01*
X1058865Y22250D01*
X1059640Y23083D01*
X1060260Y24125D01*
X1061190Y27458D01*
X1063205Y34333D01*
G01X1058245D02*
X1061190Y27458D01*
G01X1070025Y31625D02*
X1074985D01*
X1074520Y33083D01*
X1073745Y33917D01*
X1072660Y34333D01*
X1071575Y34125D01*
X1070645Y33500D01*
X1070025Y32042D01*
X1069715Y30791D01*
Y29542D01*
X1070025Y28292D01*
X1070800Y27041D01*
X1071730Y26208D01*
X1072815Y26000D01*
X1073900Y26417D01*
X1074985Y27666D01*
G01X1082580Y26000D02*
Y34333D01*
G01Y32667D02*
X1083355Y33500D01*
X1084130Y34125D01*
X1085215Y34333D01*
X1085990Y34125D01*
X1086920Y33500D01*
G01X1108620Y26000D02*
Y36625D01*
X1108930Y37666D01*
X1109550Y38292D01*
X1110480Y38500D01*
X1111410Y38083D01*
X1111875Y37042D01*
G01X1110015Y33500D02*
X1106915D01*
G01X1121950Y26000D02*
X1121020Y26208D01*
X1120090Y27041D01*
X1119470Y28500D01*
X1119160Y30167D01*
X1119470Y31833D01*
X1120090Y33292D01*
X1121020Y34125D01*
X1121950Y34333D01*
X1122880Y34125D01*
X1123810Y33292D01*
X1124430Y31833D01*
X1124585Y30167D01*
X1124430Y28500D01*
X1123810Y27041D01*
X1122880Y26208D01*
X1121950Y26000D01*
G01X1132180D02*
Y34333D01*
G01Y32667D02*
X1132955Y33500D01*
X1133730Y34125D01*
X1134815Y34333D01*
X1135590Y34125D01*
X1136520Y33500D01*
G01X1162250Y26000D02*
X1156050D01*
Y38500D01*
X1162250D01*
G01X1159770Y32458D02*
X1156050D01*
G01X1168450Y38500D02*
Y26000D01*
X1174650D01*
G01X1180850Y38500D02*
Y26000D01*
X1187050D01*
G01X1194490Y38500D02*
X1198210D01*
G01X1196350D02*
Y26000D01*
G01X1194490D02*
X1198210D01*
G01X1205650D02*
Y38500D01*
X1209370D01*
X1210610Y37875D01*
X1211540Y36417D01*
X1211850Y34750D01*
X1211540Y33083D01*
X1210765Y31833D01*
X1209370Y31208D01*
X1205650D01*
G01X1217895Y27666D02*
X1219135Y26625D01*
X1220530Y26000D01*
X1221770D01*
X1223010Y26625D01*
X1223940Y27666D01*
X1224405Y29125D01*
X1224095Y30583D01*
X1223320Y31833D01*
X1221925Y32667D01*
X1220065Y33083D01*
X1218980Y33917D01*
X1218515Y35375D01*
X1218825Y36833D01*
X1219600Y37875D01*
X1220685Y38500D01*
X1221770D01*
X1222855Y38083D01*
X1223785Y37042D01*
G01X1236650Y26000D02*
X1230450D01*
Y38500D01*
X1236650D01*
G01X1234170Y32458D02*
X1230450D01*
G01X1261140Y38500D02*
Y26000D01*
G01Y27875D02*
X1260520Y26833D01*
X1259590Y26208D01*
X1258505Y26000D01*
X1257265Y26417D01*
X1256335Y27458D01*
X1255715Y28708D01*
X1255560Y30167D01*
X1255715Y31625D01*
X1256335Y32875D01*
X1257265Y33917D01*
X1258505Y34333D01*
X1259590Y34125D01*
X1260365Y33708D01*
X1261140Y32875D01*
G01X1268580Y26000D02*
Y34333D01*
G01Y32667D02*
X1269355Y33500D01*
X1270130Y34125D01*
X1271215Y34333D01*
X1271990Y34125D01*
X1272920Y33500D01*
G01X1283150Y34333D02*
Y26000D01*
G01Y37666D02*
X1282840Y37875D01*
Y38292D01*
X1283150Y38500D01*
X1283460Y38292D01*
Y37875D01*
X1283150Y37666D01*
G01X1295550Y26000D02*
Y38500D01*
G01X1307950Y26000D02*
Y38500D01*
G01X1335540D02*
Y26000D01*
G01Y27875D02*
X1334920Y26833D01*
X1333990Y26208D01*
X1332905Y26000D01*
X1331665Y26417D01*
X1330735Y27458D01*
X1330115Y28708D01*
X1329960Y30167D01*
X1330115Y31625D01*
X1330735Y32875D01*
X1331665Y33917D01*
X1332905Y34333D01*
X1333990Y34125D01*
X1334765Y33708D01*
X1335540Y32875D01*
G01X1345150Y34333D02*
Y26000D01*
G01Y37666D02*
X1344840Y37875D01*
Y38292D01*
X1345150Y38500D01*
X1345460Y38292D01*
Y37875D01*
X1345150Y37666D01*
G01X1355380Y26000D02*
Y34333D01*
G01Y32667D02*
X1356155Y33500D01*
X1356930Y34125D01*
X1358015Y34333D01*
X1358790Y34125D01*
X1359720Y33500D01*
G01X1367625Y31625D02*
X1372585D01*
X1372120Y33083D01*
X1371345Y33917D01*
X1370260Y34333D01*
X1369175Y34125D01*
X1368245Y33500D01*
X1367625Y32042D01*
X1367315Y30791D01*
Y29542D01*
X1367625Y28292D01*
X1368400Y27041D01*
X1369330Y26208D01*
X1370415Y26000D01*
X1371500Y26417D01*
X1372585Y27666D01*
G01X1384830Y33292D02*
X1383745Y34125D01*
X1382815Y34333D01*
X1381575Y33917D01*
X1380645Y33083D01*
X1380025Y31625D01*
X1379870Y30167D01*
X1380025Y28708D01*
X1380645Y27458D01*
X1381575Y26417D01*
X1382815Y26000D01*
X1383900Y26417D01*
X1384830Y27250D01*
G01X1394750Y38500D02*
Y26000D01*
G01X1392580Y34333D02*
X1396920D01*
G01X1407150D02*
Y26000D01*
G01Y37666D02*
X1406840Y37875D01*
Y38292D01*
X1407150Y38500D01*
X1407460Y38292D01*
Y37875D01*
X1407150Y37666D01*
G01X1419550Y26000D02*
X1418620Y26208D01*
X1417690Y27041D01*
X1417070Y28500D01*
X1416760Y30167D01*
X1417070Y31833D01*
X1417690Y33292D01*
X1418620Y34125D01*
X1419550Y34333D01*
X1420480Y34125D01*
X1421410Y33292D01*
X1422030Y31833D01*
X1422185Y30167D01*
X1422030Y28500D01*
X1421410Y27041D01*
X1420480Y26208D01*
X1419550Y26000D01*
G01X1429315D02*
Y34333D01*
G01Y32250D02*
X1429935Y33292D01*
X1430865Y34125D01*
X1432105Y34333D01*
X1433190Y34125D01*
X1434120Y33292D01*
X1434585Y31833D01*
Y26000D01*
G01X782500Y56000D02*
Y362000D01*
X1266100D01*
Y56000D01*
X782500D01*
G01Y84100D02*
X1266100D01*
G01X782500Y112200D02*
X1266100D01*
G01X782500Y140300D02*
X1266100D01*
G01X782500Y168400D02*
X1266100D01*
G01X782500Y196500D02*
X1266100D01*
G01X782500Y224600D02*
X1266100D01*
G01X782500Y252700D02*
X1266100D01*
G01X793505Y290150D02*
Y302650D01*
X799395D01*
G01X797225Y296608D02*
X793505D01*
G01X806990Y302650D02*
X810710D01*
G01X808850D02*
Y290150D01*
G01X806990D02*
X810710D01*
G01X822180Y296400D02*
X825280D01*
Y292650D01*
X824350Y291400D01*
X823265Y290567D01*
X821715Y290150D01*
X820165Y290567D01*
X819080Y291400D01*
X818150Y292650D01*
X817530Y294108D01*
X817220Y295775D01*
Y297233D01*
X817530Y298483D01*
X818150Y299942D01*
X819080Y301192D01*
X820010Y302025D01*
X821250Y302650D01*
X822335D01*
X823575Y302233D01*
X824505Y301400D01*
G01X830240Y302650D02*
Y293692D01*
X830860Y291816D01*
X832100Y290567D01*
X833650Y290150D01*
X835200Y290567D01*
X836440Y291816D01*
X837060Y293692D01*
Y302650D01*
G01X842950Y290150D02*
Y302650D01*
X846825D01*
X848065Y302025D01*
X848840Y301192D01*
X849150Y299525D01*
X848840Y297858D01*
X847910Y296817D01*
X846825Y296192D01*
X842950D01*
G01X846825D02*
X849150Y290150D01*
G01X861550D02*
X855350D01*
Y302650D01*
X861550D01*
G01X859070Y296608D02*
X855350D01*
G01X782500Y280800D02*
X1266100D01*
G01X782500Y308900D02*
X1266100D01*
G01X782500Y337000D02*
X1266100D01*
G01X830008Y-224003D02*
Y-206503D01*
X834374D01*
X836121Y-207378D01*
X837431Y-208545D01*
X838523Y-210294D01*
X839396Y-212337D01*
X839614Y-215253D01*
X839396Y-218170D01*
X838523Y-220212D01*
X837431Y-221962D01*
X836121Y-223128D01*
X834374Y-224003D01*
X830008D01*
G01X849036Y-216128D02*
X856023D01*
X855368Y-214086D01*
X854276Y-212920D01*
X852748Y-212337D01*
X851219Y-212628D01*
X849909Y-213503D01*
X849036Y-215545D01*
X848599Y-217295D01*
Y-219045D01*
X849036Y-220795D01*
X850128Y-222545D01*
X851438Y-223711D01*
X852966Y-224003D01*
X854494Y-223420D01*
X856023Y-221670D01*
G01X866536Y-221962D02*
X867628Y-223128D01*
X869156Y-224003D01*
X870466D01*
X871776Y-223420D01*
X872649Y-222545D01*
X873086Y-221379D01*
X872868Y-219628D01*
X871994Y-218753D01*
X868064Y-217003D01*
X867191Y-214961D01*
X867628Y-213503D01*
X868501Y-212628D01*
X869811Y-212337D01*
X871121Y-212628D01*
X872431Y-213503D01*
G01X887311Y-212337D02*
Y-224003D01*
G01Y-207670D02*
X886874Y-207378D01*
Y-206795D01*
X887311Y-206503D01*
X887748Y-206795D01*
Y-207378D01*
X887311Y-207670D01*
G01X901754Y-228378D02*
X903283Y-229545D01*
X905029Y-229836D01*
X906557Y-229545D01*
X907868Y-228087D01*
X908741Y-226045D01*
Y-212337D01*
G01Y-214670D02*
X907868Y-213503D01*
X906557Y-212628D01*
X905029Y-212337D01*
X903283Y-212920D01*
X902191Y-214086D01*
X901317Y-216128D01*
X900881Y-218170D01*
X901099Y-219920D01*
X901973Y-221962D01*
X903283Y-223420D01*
X905029Y-224003D01*
X906339Y-223711D01*
X907868Y-222545D01*
X908741Y-221379D01*
G01X918599Y-224003D02*
Y-212337D01*
G01Y-215253D02*
X919473Y-213795D01*
X920783Y-212628D01*
X922529Y-212337D01*
X924057Y-212628D01*
X925368Y-213795D01*
X926023Y-215836D01*
Y-224003D01*
G01X936536Y-216128D02*
X943523D01*
X942868Y-214086D01*
X941776Y-212920D01*
X940248Y-212337D01*
X938719Y-212628D01*
X937409Y-213503D01*
X936536Y-215545D01*
X936099Y-217295D01*
Y-219045D01*
X936536Y-220795D01*
X937628Y-222545D01*
X938938Y-223711D01*
X940466Y-224003D01*
X941994Y-223420D01*
X943523Y-221670D01*
G01X954254Y-224003D02*
Y-212337D01*
G01Y-214670D02*
X955346Y-213503D01*
X956438Y-212628D01*
X957966Y-212337D01*
X959057Y-212628D01*
X960368Y-213503D01*
G01X865890Y343250D02*
Y355750D01*
X868990D01*
X870230Y355125D01*
X871160Y354292D01*
X871935Y353042D01*
X872555Y351583D01*
X872710Y349500D01*
X872555Y347417D01*
X871935Y345958D01*
X871160Y344708D01*
X870230Y343875D01*
X868990Y343250D01*
X865890D01*
G01X878600D02*
Y355750D01*
X882475D01*
X883715Y355125D01*
X884490Y354292D01*
X884800Y352625D01*
X884490Y350958D01*
X883560Y349917D01*
X882475Y349292D01*
X878600D01*
G01X882475D02*
X884800Y343250D01*
G01X892240Y355750D02*
X895960D01*
G01X894100D02*
Y343250D01*
G01X892240D02*
X895960D01*
G01X903400Y355750D02*
Y343250D01*
X909600D01*
G01X915800Y355750D02*
Y343250D01*
X922000D01*
G01X947110Y354708D02*
X946180Y355333D01*
X945095Y355750D01*
X943855D01*
X942460Y355125D01*
X941375Y354083D01*
X940600Y352833D01*
X939980Y350750D01*
X939825Y348875D01*
X940135Y347000D01*
X940600Y345750D01*
X941530Y344500D01*
X942615Y343667D01*
X943700Y343250D01*
X944785D01*
X945870Y343667D01*
X946800Y344291D01*
X947575Y345125D01*
G01X952845Y343250D02*
Y355750D01*
G01X959355D02*
Y343250D01*
G01Y349500D02*
X952845D01*
G01X964625Y343250D02*
X968500Y355750D01*
X972375Y343250D01*
G01X970980Y347625D02*
X966020D01*
G01X977800Y343250D02*
Y355750D01*
X981675D01*
X982915Y355125D01*
X983690Y354292D01*
X984000Y352625D01*
X983690Y350958D01*
X982760Y349917D01*
X981675Y349292D01*
X977800D01*
G01X981675D02*
X984000Y343250D01*
G01X993300Y355750D02*
Y343250D01*
G01X989735Y355750D02*
X996865D01*
G01X1005700Y342833D02*
X1005390Y343042D01*
Y343458D01*
X1005700Y343667D01*
X1006010Y343458D01*
Y343042D01*
X1005700Y342833D01*
G01Y348458D02*
X1005390Y348667D01*
Y349083D01*
X1005700Y349292D01*
X1006010Y349083D01*
Y348667D01*
X1005700Y348458D01*
G01X1030500Y355750D02*
Y343250D01*
G01X1026935Y355750D02*
X1034065D01*
G01X1042900Y343250D02*
X1041660Y343458D01*
X1040575Y344291D01*
X1039645Y345542D01*
X1039025Y347000D01*
X1038715Y348667D01*
Y350333D01*
X1039025Y352000D01*
X1039645Y353458D01*
X1040575Y354708D01*
X1041660Y355542D01*
X1042900Y355750D01*
X1044140Y355542D01*
X1045225Y354708D01*
X1046155Y353458D01*
X1046775Y352000D01*
X1047085Y350333D01*
Y348667D01*
X1046775Y347000D01*
X1046155Y345542D01*
X1045225Y344291D01*
X1044140Y343458D01*
X1042900Y343250D01*
G01X1052200D02*
Y355750D01*
X1055920D01*
X1057160Y355125D01*
X1058090Y353667D01*
X1058400Y352000D01*
X1058090Y350333D01*
X1057315Y349083D01*
X1055920Y348458D01*
X1052200D01*
G01X1080100Y355750D02*
Y343250D01*
G01X1077930Y351583D02*
X1082270D01*
G01X1092500Y343250D02*
X1091570Y343458D01*
X1090640Y344291D01*
X1090020Y345750D01*
X1089710Y347417D01*
X1090020Y349083D01*
X1090640Y350542D01*
X1091570Y351375D01*
X1092500Y351583D01*
X1093430Y351375D01*
X1094360Y350542D01*
X1094980Y349083D01*
X1095135Y347417D01*
X1094980Y345750D01*
X1094360Y344291D01*
X1093430Y343458D01*
X1092500Y343250D01*
G01X1118540Y349917D02*
X1119160Y350542D01*
X1119625Y351583D01*
X1119935Y353042D01*
X1119625Y354292D01*
X1119005Y355125D01*
X1117920Y355750D01*
X1113735D01*
Y343250D01*
X1118850D01*
X1119935Y344083D01*
X1120555Y345333D01*
X1120865Y346792D01*
X1120555Y348250D01*
X1119625Y349500D01*
X1118540Y349917D01*
X1113735D01*
G01X1129700Y343250D02*
X1128460Y343458D01*
X1127375Y344291D01*
X1126445Y345542D01*
X1125825Y347000D01*
X1125515Y348667D01*
Y350333D01*
X1125825Y352000D01*
X1126445Y353458D01*
X1127375Y354708D01*
X1128460Y355542D01*
X1129700Y355750D01*
X1130940Y355542D01*
X1132025Y354708D01*
X1132955Y353458D01*
X1133575Y352000D01*
X1133885Y350333D01*
Y348667D01*
X1133575Y347000D01*
X1132955Y345542D01*
X1132025Y344291D01*
X1130940Y343458D01*
X1129700Y343250D01*
G01X1142100Y355750D02*
Y343250D01*
G01X1138535Y355750D02*
X1145665D01*
G01X1154500D02*
Y343250D01*
G01X1150935Y355750D02*
X1158065D01*
G01X1166900Y343250D02*
X1165660Y343458D01*
X1164575Y344291D01*
X1163645Y345542D01*
X1163025Y347000D01*
X1162715Y348667D01*
Y350333D01*
X1163025Y352000D01*
X1163645Y353458D01*
X1164575Y354708D01*
X1165660Y355542D01*
X1166900Y355750D01*
X1168140Y355542D01*
X1169225Y354708D01*
X1170155Y353458D01*
X1170775Y352000D01*
X1171085Y350333D01*
Y348667D01*
X1170775Y347000D01*
X1170155Y345542D01*
X1169225Y344291D01*
X1168140Y343458D01*
X1166900Y343250D01*
G01X1175270D02*
Y355750D01*
X1179300Y345333D01*
X1183330Y355750D01*
Y343250D01*
G01X874194Y-265503D02*
X875286Y-267253D01*
X876596Y-268420D01*
X878124Y-269003D01*
X879871Y-268420D01*
X881181Y-267253D01*
X882491Y-265503D01*
X882928Y-263170D01*
Y-251503D01*
G01X896061Y-269003D02*
X894314Y-268711D01*
X892786Y-267545D01*
X891476Y-265795D01*
X890602Y-263753D01*
X890166Y-261420D01*
Y-259086D01*
X890602Y-256753D01*
X891476Y-254711D01*
X892786Y-252962D01*
X894314Y-251795D01*
X896061Y-251503D01*
X897807Y-251795D01*
X899336Y-252962D01*
X900646Y-254711D01*
X901520Y-256753D01*
X901956Y-259086D01*
Y-261420D01*
X901520Y-263753D01*
X900646Y-265795D01*
X899336Y-267545D01*
X897807Y-268711D01*
X896061Y-269003D01*
G01X913561D02*
Y-261128D01*
X909194Y-251503D01*
G01X917928D02*
X913561Y-261128D01*
G01X872400Y308900D02*
Y56000D01*
G01X896425Y318250D02*
X900300Y330750D01*
X904175Y318250D01*
G01X902780Y322625D02*
X897820D01*
G01X909600Y330750D02*
Y318250D01*
X915800D01*
G01X922000Y330750D02*
Y318250D01*
X928200D01*
G01X946490Y330750D02*
Y321792D01*
X947110Y319916D01*
X948350Y318667D01*
X949900Y318250D01*
X951450Y318667D01*
X952690Y319916D01*
X953310Y321792D01*
Y330750D01*
G01X958735Y318250D02*
Y330750D01*
X965865Y318250D01*
Y330750D01*
G01X972840D02*
X976560D01*
G01X974700D02*
Y318250D01*
G01X972840D02*
X976560D01*
G01X987100Y330750D02*
Y318250D01*
G01X983535Y330750D02*
X990665D01*
G01X996245Y319916D02*
X997485Y318875D01*
X998880Y318250D01*
X1000120D01*
X1001360Y318875D01*
X1002290Y319916D01*
X1002755Y321375D01*
X1002445Y322833D01*
X1001670Y324083D01*
X1000275Y324917D01*
X998415Y325333D01*
X997330Y326167D01*
X996865Y327625D01*
X997175Y329083D01*
X997950Y330125D01*
X999035Y330750D01*
X1000120D01*
X1001205Y330333D01*
X1002135Y329292D01*
G01X1020425Y318250D02*
X1024300Y330750D01*
X1028175Y318250D01*
G01X1026780Y322625D02*
X1021820D01*
G01X1033600Y318250D02*
Y330750D01*
X1037475D01*
X1038715Y330125D01*
X1039490Y329292D01*
X1039800Y327625D01*
X1039490Y325958D01*
X1038560Y324917D01*
X1037475Y324292D01*
X1033600D01*
G01X1037475D02*
X1039800Y318250D01*
G01X1052200D02*
X1046000D01*
Y330750D01*
X1052200D01*
G01X1049720Y324708D02*
X1046000D01*
G01X1072040Y330750D02*
X1075760D01*
G01X1073900D02*
Y318250D01*
G01X1072040D02*
X1075760D01*
G01X1082735D02*
Y330750D01*
X1089865Y318250D01*
Y330750D01*
G01X1107070Y318250D02*
Y330750D01*
X1111100Y320333D01*
X1115130Y330750D01*
Y318250D01*
G01X1121640Y330750D02*
X1125360D01*
G01X1123500D02*
Y318250D01*
G01X1121640D02*
X1125360D01*
G01X1132800Y330750D02*
Y318250D01*
X1139000D01*
G01X1145045Y319916D02*
X1146285Y318875D01*
X1147680Y318250D01*
X1148920D01*
X1150160Y318875D01*
X1151090Y319916D01*
X1151555Y321375D01*
X1151245Y322833D01*
X1150470Y324083D01*
X1149075Y324917D01*
X1147215Y325333D01*
X1146130Y326167D01*
X1145665Y327625D01*
X1145975Y329083D01*
X1146750Y330125D01*
X1147835Y330750D01*
X1148920D01*
X1150005Y330333D01*
X1150935Y329292D01*
G01X948350Y63800D02*
X949435Y64008D01*
X950675Y64633D01*
X951450Y65675D01*
X951760Y67133D01*
X951450Y68591D01*
X950520Y69842D01*
X949125Y70467D01*
X947575D01*
X946645Y70883D01*
X945870Y71925D01*
X945560Y73383D01*
X946025Y74842D01*
X947110Y75883D01*
X948350Y76300D01*
X949590Y75883D01*
X950675Y74842D01*
X951140Y73383D01*
X950830Y71925D01*
X950055Y70883D01*
X949125Y70467D01*
X947575D01*
X946180Y69842D01*
X945250Y68591D01*
X944940Y67133D01*
X945250Y65675D01*
X946025Y64633D01*
X947265Y64008D01*
X948350Y63800D01*
G01X957805Y69008D02*
X958890Y70467D01*
X959820Y71300D01*
X961060Y71717D01*
X962145Y71300D01*
X962920Y70467D01*
X963540Y69217D01*
X963695Y67758D01*
X963540Y66508D01*
X962920Y65258D01*
X961990Y64217D01*
X960905Y63800D01*
X959665Y64217D01*
X958580Y65466D01*
X957960Y67342D01*
X957805Y69425D01*
X958115Y72133D01*
X958580Y73592D01*
X959355Y75050D01*
X960440Y76092D01*
X961525Y76300D01*
X962610Y75883D01*
X963385Y74842D01*
G01X973150Y63383D02*
X972840Y63592D01*
Y64008D01*
X973150Y64217D01*
X973460Y64008D01*
Y63592D01*
X973150Y63383D01*
G01X985550Y76300D02*
X984310Y75883D01*
X983380Y74842D01*
X982760Y73592D01*
X982295Y71925D01*
X982140Y70050D01*
X982295Y68175D01*
X982760Y66508D01*
X983380Y65258D01*
X984310Y64217D01*
X985550Y63800D01*
X986790Y64217D01*
X987720Y65258D01*
X988340Y66508D01*
X988805Y68175D01*
X988960Y70050D01*
X988805Y71925D01*
X988340Y73592D01*
X987720Y74842D01*
X986790Y75883D01*
X985550Y76300D01*
G01X945405Y97108D02*
X946490Y98567D01*
X947420Y99400D01*
X948660Y99817D01*
X949745Y99400D01*
X950520Y98567D01*
X951140Y97317D01*
X951295Y95858D01*
X951140Y94608D01*
X950520Y93358D01*
X949590Y92317D01*
X948505Y91900D01*
X947265Y92317D01*
X946180Y93566D01*
X945560Y95442D01*
X945405Y97525D01*
X945715Y100233D01*
X946180Y101692D01*
X946955Y103150D01*
X948040Y104192D01*
X949125Y104400D01*
X950210Y103983D01*
X950985Y102942D01*
G01X957340Y93775D02*
X958270Y92733D01*
X959355Y92108D01*
X960750Y91900D01*
X962145Y92317D01*
X963230Y93150D01*
X964005Y94608D01*
X964160Y96275D01*
X963850Y97942D01*
X963075Y98983D01*
X961990Y99817D01*
X960905Y100025D01*
X959820Y99817D01*
X958425Y98983D01*
X958890Y104400D01*
X963075D01*
G01X973150Y91483D02*
X972840Y91692D01*
Y92108D01*
X973150Y92317D01*
X973460Y92108D01*
Y91692D01*
X973150Y91483D01*
G01X985550Y104400D02*
X984310Y103983D01*
X983380Y102942D01*
X982760Y101692D01*
X982295Y100025D01*
X982140Y98150D01*
X982295Y96275D01*
X982760Y94608D01*
X983380Y93358D01*
X984310Y92317D01*
X985550Y91900D01*
X986790Y92317D01*
X987720Y93358D01*
X988340Y94608D01*
X988805Y96275D01*
X988960Y98150D01*
X988805Y100025D01*
X988340Y101692D01*
X987720Y102942D01*
X986790Y103983D01*
X985550Y104400D01*
G01X945405Y125208D02*
X946490Y126667D01*
X947420Y127500D01*
X948660Y127917D01*
X949745Y127500D01*
X950520Y126667D01*
X951140Y125417D01*
X951295Y123958D01*
X951140Y122708D01*
X950520Y121458D01*
X949590Y120417D01*
X948505Y120000D01*
X947265Y120417D01*
X946180Y121666D01*
X945560Y123542D01*
X945405Y125625D01*
X945715Y128333D01*
X946180Y129792D01*
X946955Y131250D01*
X948040Y132292D01*
X949125Y132500D01*
X950210Y132083D01*
X950985Y131042D01*
G01X957340Y122500D02*
X958270Y121041D01*
X959510Y120208D01*
X960905Y120000D01*
X962145Y120208D01*
X963385Y121250D01*
X964160Y122500D01*
X964315Y123750D01*
X964005Y125208D01*
X962920Y126250D01*
X961835Y126667D01*
X960440D01*
G01X961835D02*
X962765Y127292D01*
X963540Y128333D01*
X963850Y129583D01*
X963540Y130833D01*
X962765Y131875D01*
X961370Y132500D01*
X959975Y132292D01*
X958580Y131458D01*
G01X973150Y119583D02*
X972840Y119792D01*
Y120208D01*
X973150Y120417D01*
X973460Y120208D01*
Y119792D01*
X973150Y119583D01*
G01X985550Y132500D02*
X984310Y132083D01*
X983380Y131042D01*
X982760Y129792D01*
X982295Y128125D01*
X982140Y126250D01*
X982295Y124375D01*
X982760Y122708D01*
X983380Y121458D01*
X984310Y120417D01*
X985550Y120000D01*
X986790Y120417D01*
X987720Y121458D01*
X988340Y122708D01*
X988805Y124375D01*
X988960Y126250D01*
X988805Y128125D01*
X988340Y129792D01*
X987720Y131042D01*
X986790Y132083D01*
X985550Y132500D01*
G01X950210Y148100D02*
Y160600D01*
X944475Y151642D01*
X952225D01*
G01X962610Y148100D02*
Y160600D01*
X956875Y151642D01*
X964625D01*
G01X973150Y147683D02*
X972840Y147892D01*
Y148308D01*
X973150Y148517D01*
X973460Y148308D01*
Y147892D01*
X973150Y147683D01*
G01X985550Y160600D02*
X984310Y160183D01*
X983380Y159142D01*
X982760Y157892D01*
X982295Y156225D01*
X982140Y154350D01*
X982295Y152475D01*
X982760Y150808D01*
X983380Y149558D01*
X984310Y148517D01*
X985550Y148100D01*
X986790Y148517D01*
X987720Y149558D01*
X988340Y150808D01*
X988805Y152475D01*
X988960Y154350D01*
X988805Y156225D01*
X988340Y157892D01*
X987720Y159142D01*
X986790Y160183D01*
X985550Y160600D01*
G01X942150Y176200D02*
Y188700D01*
X940290Y186200D01*
G01Y176200D02*
X944010D01*
G01X956410D02*
Y188700D01*
X950675Y179742D01*
X958425D01*
G01X966950Y188700D02*
X965710Y188283D01*
X964780Y187242D01*
X964160Y185992D01*
X963695Y184325D01*
X963540Y182450D01*
X963695Y180575D01*
X964160Y178908D01*
X964780Y177658D01*
X965710Y176617D01*
X966950Y176200D01*
X968190Y176617D01*
X969120Y177658D01*
X969740Y178908D01*
X970205Y180575D01*
X970360Y182450D01*
X970205Y184325D01*
X969740Y185992D01*
X969120Y187242D01*
X968190Y188283D01*
X966950Y188700D01*
G01X979350Y175783D02*
X979040Y175992D01*
Y176408D01*
X979350Y176617D01*
X979660Y176408D01*
Y175992D01*
X979350Y175783D01*
G01X991750Y188700D02*
X990510Y188283D01*
X989580Y187242D01*
X988960Y185992D01*
X988495Y184325D01*
X988340Y182450D01*
X988495Y180575D01*
X988960Y178908D01*
X989580Y177658D01*
X990510Y176617D01*
X991750Y176200D01*
X992990Y176617D01*
X993920Y177658D01*
X994540Y178908D01*
X995005Y180575D01*
X995160Y182450D01*
X995005Y184325D01*
X994540Y185992D01*
X993920Y187242D01*
X992990Y188283D01*
X991750Y188700D01*
G01X950210Y204300D02*
Y216800D01*
X944475Y207842D01*
X952225D01*
G01X960750Y216800D02*
X959510Y216383D01*
X958580Y215342D01*
X957960Y214092D01*
X957495Y212425D01*
X957340Y210550D01*
X957495Y208675D01*
X957960Y207008D01*
X958580Y205758D01*
X959510Y204717D01*
X960750Y204300D01*
X961990Y204717D01*
X962920Y205758D01*
X963540Y207008D01*
X964005Y208675D01*
X964160Y210550D01*
X964005Y212425D01*
X963540Y214092D01*
X962920Y215342D01*
X961990Y216383D01*
X960750Y216800D01*
G01X973150Y203883D02*
X972840Y204092D01*
Y204508D01*
X973150Y204717D01*
X973460Y204508D01*
Y204092D01*
X973150Y203883D01*
G01X985550Y216800D02*
X984310Y216383D01*
X983380Y215342D01*
X982760Y214092D01*
X982295Y212425D01*
X982140Y210550D01*
X982295Y208675D01*
X982760Y207008D01*
X983380Y205758D01*
X984310Y204717D01*
X985550Y204300D01*
X986790Y204717D01*
X987720Y205758D01*
X988340Y207008D01*
X988805Y208675D01*
X988960Y210550D01*
X988805Y212425D01*
X988340Y214092D01*
X987720Y215342D01*
X986790Y216383D01*
X985550Y216800D01*
G01X948350Y232400D02*
Y244900D01*
X946490Y242400D01*
G01Y232400D02*
X950210D01*
G01X957805Y242817D02*
X958735Y244066D01*
X959820Y244692D01*
X961060Y244900D01*
X962610Y244483D01*
X963695Y243442D01*
X964005Y242192D01*
X963850Y240941D01*
X963230Y239900D01*
X960130Y237817D01*
X958735Y236358D01*
X957805Y234275D01*
X957495Y232400D01*
X964005D01*
G01X973150Y231983D02*
X972840Y232192D01*
Y232608D01*
X973150Y232817D01*
X973460Y232608D01*
Y232192D01*
X973150Y231983D01*
G01X985550Y244900D02*
X984310Y244483D01*
X983380Y243442D01*
X982760Y242192D01*
X982295Y240525D01*
X982140Y238650D01*
X982295Y236775D01*
X982760Y235108D01*
X983380Y233858D01*
X984310Y232817D01*
X985550Y232400D01*
X986790Y232817D01*
X987720Y233858D01*
X988340Y235108D01*
X988805Y236775D01*
X988960Y238650D01*
X988805Y240525D01*
X988340Y242192D01*
X987720Y243442D01*
X986790Y244483D01*
X985550Y244900D01*
G01X948350Y260500D02*
Y273000D01*
X946490Y270500D01*
G01Y260500D02*
X950210D01*
G01X960750Y273000D02*
X959510Y272583D01*
X958580Y271542D01*
X957960Y270292D01*
X957495Y268625D01*
X957340Y266750D01*
X957495Y264875D01*
X957960Y263208D01*
X958580Y261958D01*
X959510Y260917D01*
X960750Y260500D01*
X961990Y260917D01*
X962920Y261958D01*
X963540Y263208D01*
X964005Y264875D01*
X964160Y266750D01*
X964005Y268625D01*
X963540Y270292D01*
X962920Y271542D01*
X961990Y272583D01*
X960750Y273000D01*
G01X973150Y260083D02*
X972840Y260292D01*
Y260708D01*
X973150Y260917D01*
X973460Y260708D01*
Y260292D01*
X973150Y260083D01*
G01X985550Y273000D02*
X984310Y272583D01*
X983380Y271542D01*
X982760Y270292D01*
X982295Y268625D01*
X982140Y266750D01*
X982295Y264875D01*
X982760Y263208D01*
X983380Y261958D01*
X984310Y260917D01*
X985550Y260500D01*
X986790Y260917D01*
X987720Y261958D01*
X988340Y263208D01*
X988805Y264875D01*
X988960Y266750D01*
X988805Y268625D01*
X988340Y270292D01*
X987720Y271542D01*
X986790Y272583D01*
X985550Y273000D01*
G01X945095Y291816D02*
X946335Y290775D01*
X947730Y290150D01*
X948970D01*
X950210Y290775D01*
X951140Y291816D01*
X951605Y293275D01*
X951295Y294733D01*
X950520Y295983D01*
X949125Y296817D01*
X947265Y297233D01*
X946180Y298067D01*
X945715Y299525D01*
X946025Y300983D01*
X946800Y302025D01*
X947885Y302650D01*
X948970D01*
X950055Y302233D01*
X950985Y301192D01*
G01X958890Y302650D02*
X962610D01*
G01X960750D02*
Y290150D01*
G01X958890D02*
X962610D01*
G01X970205Y302650D02*
X976095D01*
X970205Y290150D01*
X976095D01*
G01X988650D02*
X982450D01*
Y302650D01*
X988650D01*
G01X986170Y296608D02*
X982450D01*
G01X1001011Y-269003D02*
Y-251503D01*
X998391Y-255003D01*
G01Y-269003D02*
X1003631D01*
G01X1014363Y-254420D02*
X1015673Y-252670D01*
X1017201Y-251795D01*
X1018948Y-251503D01*
X1021131Y-252086D01*
X1022659Y-253545D01*
X1023096Y-255294D01*
X1022878Y-257045D01*
X1022004Y-258503D01*
X1017638Y-261420D01*
X1015673Y-263461D01*
X1014363Y-266379D01*
X1013926Y-269003D01*
X1023096D01*
G01X1032081Y-269586D02*
X1039941Y-251503D01*
G01X1048708Y-265503D02*
X1050017Y-267545D01*
X1051764Y-268711D01*
X1053729Y-269003D01*
X1055476Y-268711D01*
X1057223Y-267253D01*
X1058314Y-265503D01*
X1058533Y-263753D01*
X1058096Y-261712D01*
X1056568Y-260253D01*
X1055039Y-259670D01*
X1053074D01*
G01X1055039D02*
X1056349Y-258795D01*
X1057441Y-257337D01*
X1057878Y-255587D01*
X1057441Y-253836D01*
X1056349Y-252378D01*
X1054384Y-251503D01*
X1052419Y-251795D01*
X1050454Y-252962D01*
G01X1071011Y-251503D02*
X1069264Y-252086D01*
X1067954Y-253545D01*
X1067081Y-255294D01*
X1066426Y-257628D01*
X1066208Y-260253D01*
X1066426Y-262878D01*
X1067081Y-265212D01*
X1067954Y-266962D01*
X1069264Y-268420D01*
X1071011Y-269003D01*
X1072757Y-268420D01*
X1074068Y-266962D01*
X1074941Y-265212D01*
X1075596Y-262878D01*
X1075814Y-260253D01*
X1075596Y-257628D01*
X1074941Y-255294D01*
X1074068Y-253545D01*
X1072757Y-252086D01*
X1071011Y-251503D01*
G01X1084581Y-269586D02*
X1092441Y-251503D01*
G01X1101863Y-254420D02*
X1103173Y-252670D01*
X1104701Y-251795D01*
X1106448Y-251503D01*
X1108631Y-252086D01*
X1110159Y-253545D01*
X1110596Y-255294D01*
X1110378Y-257045D01*
X1109504Y-258503D01*
X1105138Y-261420D01*
X1103173Y-263461D01*
X1101863Y-266379D01*
X1101426Y-269003D01*
X1110596D01*
G01X1123511Y-251503D02*
X1121764Y-252086D01*
X1120454Y-253545D01*
X1119581Y-255294D01*
X1118926Y-257628D01*
X1118708Y-260253D01*
X1118926Y-262878D01*
X1119581Y-265212D01*
X1120454Y-266962D01*
X1121764Y-268420D01*
X1123511Y-269003D01*
X1125257Y-268420D01*
X1126568Y-266962D01*
X1127441Y-265212D01*
X1128096Y-262878D01*
X1128314Y-260253D01*
X1128096Y-257628D01*
X1127441Y-255294D01*
X1126568Y-253545D01*
X1125257Y-252086D01*
X1123511Y-251503D01*
G01X1141011Y-269003D02*
Y-251503D01*
X1138391Y-255003D01*
G01Y-269003D02*
X1143631D01*
G01X1154363Y-261712D02*
X1155891Y-259670D01*
X1157201Y-258503D01*
X1158948Y-257920D01*
X1160476Y-258503D01*
X1161568Y-259670D01*
X1162441Y-261420D01*
X1162659Y-263461D01*
X1162441Y-265212D01*
X1161568Y-266962D01*
X1160257Y-268420D01*
X1158729Y-269003D01*
X1156983Y-268420D01*
X1155454Y-266670D01*
X1154581Y-264045D01*
X1154363Y-261128D01*
X1154799Y-257337D01*
X1155454Y-255294D01*
X1156546Y-253253D01*
X1158074Y-251795D01*
X1159603Y-251503D01*
X1161131Y-252086D01*
X1162223Y-253545D01*
G01X1048708Y-224003D02*
Y-206503D01*
X1053074D01*
X1054821Y-207378D01*
X1056131Y-208545D01*
X1057223Y-210294D01*
X1058096Y-212337D01*
X1058314Y-215253D01*
X1058096Y-218170D01*
X1057223Y-220212D01*
X1056131Y-221962D01*
X1054821Y-223128D01*
X1053074Y-224003D01*
X1048708D01*
G01X1074941D02*
Y-212337D01*
G01Y-214378D02*
X1074068Y-213212D01*
X1072757Y-212628D01*
X1071229Y-212337D01*
X1069701Y-212920D01*
X1068391Y-214086D01*
X1067517Y-215836D01*
X1067081Y-218170D01*
X1067517Y-220503D01*
X1068391Y-222253D01*
X1069701Y-223420D01*
X1071229Y-224003D01*
X1072757Y-223711D01*
X1074068Y-222837D01*
X1074941Y-221670D01*
G01X1088511Y-206503D02*
Y-224003D01*
G01X1085454Y-212337D02*
X1091568D01*
G01X1102736Y-216128D02*
X1109723D01*
X1109068Y-214086D01*
X1107976Y-212920D01*
X1106448Y-212337D01*
X1104919Y-212628D01*
X1103609Y-213503D01*
X1102736Y-215545D01*
X1102299Y-217295D01*
Y-219045D01*
X1102736Y-220795D01*
X1103828Y-222545D01*
X1105138Y-223711D01*
X1106666Y-224003D01*
X1108194Y-223420D01*
X1109723Y-221670D01*
G01X1061500Y308900D02*
Y56000D01*
G01X1065685Y63800D02*
Y76300D01*
X1072815Y63800D01*
Y76300D01*
G01X1081650Y63800D02*
X1080410Y64008D01*
X1079325Y64841D01*
X1078395Y66092D01*
X1077775Y67550D01*
X1077465Y69217D01*
Y70883D01*
X1077775Y72550D01*
X1078395Y74008D01*
X1079325Y75258D01*
X1080410Y76092D01*
X1081650Y76300D01*
X1082890Y76092D01*
X1083975Y75258D01*
X1084905Y74008D01*
X1085525Y72550D01*
X1085835Y70883D01*
Y69217D01*
X1085525Y67550D01*
X1084905Y66092D01*
X1083975Y64841D01*
X1082890Y64008D01*
X1081650Y63800D01*
G01X1090485D02*
Y76300D01*
X1097615Y63800D01*
Y76300D01*
G01X1104435Y67967D02*
X1108465D01*
G01X1115750Y63800D02*
Y76300D01*
X1119470D01*
X1120710Y75675D01*
X1121640Y74217D01*
X1121950Y72550D01*
X1121640Y70883D01*
X1120865Y69633D01*
X1119470Y69008D01*
X1115750D01*
G01X1128150Y76300D02*
Y63800D01*
X1134350D01*
G01X1139775D02*
X1143650Y76300D01*
X1147525Y63800D01*
G01X1146130Y68175D02*
X1141170D01*
G01X1156050Y76300D02*
Y63800D01*
G01X1152485Y76300D02*
X1159615D01*
G01X1171550Y63800D02*
X1165350D01*
Y76300D01*
X1171550D01*
G01X1169070Y70258D02*
X1165350D01*
G01X1177440Y63800D02*
Y76300D01*
X1180540D01*
X1181780Y75675D01*
X1182710Y74842D01*
X1183485Y73592D01*
X1184105Y72133D01*
X1184260Y70050D01*
X1184105Y67967D01*
X1183485Y66508D01*
X1182710Y65258D01*
X1181780Y64425D01*
X1180540Y63800D01*
X1177440D01*
G01X1065685Y91900D02*
Y104400D01*
X1072815Y91900D01*
Y104400D01*
G01X1081650Y91900D02*
X1080410Y92108D01*
X1079325Y92941D01*
X1078395Y94192D01*
X1077775Y95650D01*
X1077465Y97317D01*
Y98983D01*
X1077775Y100650D01*
X1078395Y102108D01*
X1079325Y103358D01*
X1080410Y104192D01*
X1081650Y104400D01*
X1082890Y104192D01*
X1083975Y103358D01*
X1084905Y102108D01*
X1085525Y100650D01*
X1085835Y98983D01*
Y97317D01*
X1085525Y95650D01*
X1084905Y94192D01*
X1083975Y92941D01*
X1082890Y92108D01*
X1081650Y91900D01*
G01X1090485D02*
Y104400D01*
X1097615Y91900D01*
Y104400D01*
G01X1104435Y96067D02*
X1108465D01*
G01X1115750Y91900D02*
Y104400D01*
X1119470D01*
X1120710Y103775D01*
X1121640Y102317D01*
X1121950Y100650D01*
X1121640Y98983D01*
X1120865Y97733D01*
X1119470Y97108D01*
X1115750D01*
G01X1128150Y104400D02*
Y91900D01*
X1134350D01*
G01X1139775D02*
X1143650Y104400D01*
X1147525Y91900D01*
G01X1146130Y96275D02*
X1141170D01*
G01X1156050Y104400D02*
Y91900D01*
G01X1152485Y104400D02*
X1159615D01*
G01X1171550Y91900D02*
X1165350D01*
Y104400D01*
X1171550D01*
G01X1169070Y98358D02*
X1165350D01*
G01X1177440Y91900D02*
Y104400D01*
X1180540D01*
X1181780Y103775D01*
X1182710Y102942D01*
X1183485Y101692D01*
X1184105Y100233D01*
X1184260Y98150D01*
X1184105Y96067D01*
X1183485Y94608D01*
X1182710Y93358D01*
X1181780Y92525D01*
X1180540Y91900D01*
X1177440D01*
G01X1065685Y120000D02*
Y132500D01*
X1072815Y120000D01*
Y132500D01*
G01X1081650Y120000D02*
X1080410Y120208D01*
X1079325Y121041D01*
X1078395Y122292D01*
X1077775Y123750D01*
X1077465Y125417D01*
Y127083D01*
X1077775Y128750D01*
X1078395Y130208D01*
X1079325Y131458D01*
X1080410Y132292D01*
X1081650Y132500D01*
X1082890Y132292D01*
X1083975Y131458D01*
X1084905Y130208D01*
X1085525Y128750D01*
X1085835Y127083D01*
Y125417D01*
X1085525Y123750D01*
X1084905Y122292D01*
X1083975Y121041D01*
X1082890Y120208D01*
X1081650Y120000D01*
G01X1090485D02*
Y132500D01*
X1097615Y120000D01*
Y132500D01*
G01X1104435Y124167D02*
X1108465D01*
G01X1115750Y120000D02*
Y132500D01*
X1119470D01*
X1120710Y131875D01*
X1121640Y130417D01*
X1121950Y128750D01*
X1121640Y127083D01*
X1120865Y125833D01*
X1119470Y125208D01*
X1115750D01*
G01X1128150Y132500D02*
Y120000D01*
X1134350D01*
G01X1139775D02*
X1143650Y132500D01*
X1147525Y120000D01*
G01X1146130Y124375D02*
X1141170D01*
G01X1156050Y132500D02*
Y120000D01*
G01X1152485Y132500D02*
X1159615D01*
G01X1171550Y120000D02*
X1165350D01*
Y132500D01*
X1171550D01*
G01X1169070Y126458D02*
X1165350D01*
G01X1177440Y120000D02*
Y132500D01*
X1180540D01*
X1181780Y131875D01*
X1182710Y131042D01*
X1183485Y129792D01*
X1184105Y128333D01*
X1184260Y126250D01*
X1184105Y124167D01*
X1183485Y122708D01*
X1182710Y121458D01*
X1181780Y120625D01*
X1180540Y120000D01*
X1177440D01*
G01X1065685Y148100D02*
Y160600D01*
X1072815Y148100D01*
Y160600D01*
G01X1081650Y148100D02*
X1080410Y148308D01*
X1079325Y149141D01*
X1078395Y150392D01*
X1077775Y151850D01*
X1077465Y153517D01*
Y155183D01*
X1077775Y156850D01*
X1078395Y158308D01*
X1079325Y159558D01*
X1080410Y160392D01*
X1081650Y160600D01*
X1082890Y160392D01*
X1083975Y159558D01*
X1084905Y158308D01*
X1085525Y156850D01*
X1085835Y155183D01*
Y153517D01*
X1085525Y151850D01*
X1084905Y150392D01*
X1083975Y149141D01*
X1082890Y148308D01*
X1081650Y148100D01*
G01X1090485D02*
Y160600D01*
X1097615Y148100D01*
Y160600D01*
G01X1104435Y152267D02*
X1108465D01*
G01X1115750Y148100D02*
Y160600D01*
X1119470D01*
X1120710Y159975D01*
X1121640Y158517D01*
X1121950Y156850D01*
X1121640Y155183D01*
X1120865Y153933D01*
X1119470Y153308D01*
X1115750D01*
G01X1128150Y160600D02*
Y148100D01*
X1134350D01*
G01X1139775D02*
X1143650Y160600D01*
X1147525Y148100D01*
G01X1146130Y152475D02*
X1141170D01*
G01X1156050Y160600D02*
Y148100D01*
G01X1152485Y160600D02*
X1159615D01*
G01X1171550Y148100D02*
X1165350D01*
Y160600D01*
X1171550D01*
G01X1169070Y154558D02*
X1165350D01*
G01X1177440Y148100D02*
Y160600D01*
X1180540D01*
X1181780Y159975D01*
X1182710Y159142D01*
X1183485Y157892D01*
X1184105Y156433D01*
X1184260Y154350D01*
X1184105Y152267D01*
X1183485Y150808D01*
X1182710Y149558D01*
X1181780Y148725D01*
X1180540Y148100D01*
X1177440D01*
G01X1090950Y176200D02*
Y188700D01*
X1094670D01*
X1095910Y188075D01*
X1096840Y186617D01*
X1097150Y184950D01*
X1096840Y183283D01*
X1096065Y182033D01*
X1094670Y181408D01*
X1090950D01*
G01X1103350Y188700D02*
Y176200D01*
X1109550D01*
G01X1114975D02*
X1118850Y188700D01*
X1122725Y176200D01*
G01X1121330Y180575D02*
X1116370D01*
G01X1131250Y188700D02*
Y176200D01*
G01X1127685Y188700D02*
X1134815D01*
G01X1146750Y176200D02*
X1140550D01*
Y188700D01*
X1146750D01*
G01X1144270Y182658D02*
X1140550D01*
G01X1152640Y176200D02*
Y188700D01*
X1155740D01*
X1156980Y188075D01*
X1157910Y187242D01*
X1158685Y185992D01*
X1159305Y184533D01*
X1159460Y182450D01*
X1159305Y180367D01*
X1158685Y178908D01*
X1157910Y177658D01*
X1156980Y176825D01*
X1155740Y176200D01*
X1152640D01*
G01X1090950Y204300D02*
Y216800D01*
X1094670D01*
X1095910Y216175D01*
X1096840Y214717D01*
X1097150Y213050D01*
X1096840Y211383D01*
X1096065Y210133D01*
X1094670Y209508D01*
X1090950D01*
G01X1103350Y216800D02*
Y204300D01*
X1109550D01*
G01X1114975D02*
X1118850Y216800D01*
X1122725Y204300D01*
G01X1121330Y208675D02*
X1116370D01*
G01X1131250Y216800D02*
Y204300D01*
G01X1127685Y216800D02*
X1134815D01*
G01X1146750Y204300D02*
X1140550D01*
Y216800D01*
X1146750D01*
G01X1144270Y210758D02*
X1140550D01*
G01X1152640Y204300D02*
Y216800D01*
X1155740D01*
X1156980Y216175D01*
X1157910Y215342D01*
X1158685Y214092D01*
X1159305Y212633D01*
X1159460Y210550D01*
X1159305Y208467D01*
X1158685Y207008D01*
X1157910Y205758D01*
X1156980Y204925D01*
X1155740Y204300D01*
X1152640D01*
G01X1090950Y232400D02*
Y244900D01*
X1094670D01*
X1095910Y244275D01*
X1096840Y242817D01*
X1097150Y241150D01*
X1096840Y239483D01*
X1096065Y238233D01*
X1094670Y237608D01*
X1090950D01*
G01X1103350Y244900D02*
Y232400D01*
X1109550D01*
G01X1114975D02*
X1118850Y244900D01*
X1122725Y232400D01*
G01X1121330Y236775D02*
X1116370D01*
G01X1131250Y244900D02*
Y232400D01*
G01X1127685Y244900D02*
X1134815D01*
G01X1146750Y232400D02*
X1140550D01*
Y244900D01*
X1146750D01*
G01X1144270Y238858D02*
X1140550D01*
G01X1152640Y232400D02*
Y244900D01*
X1155740D01*
X1156980Y244275D01*
X1157910Y243442D01*
X1158685Y242192D01*
X1159305Y240733D01*
X1159460Y238650D01*
X1159305Y236567D01*
X1158685Y235108D01*
X1157910Y233858D01*
X1156980Y233025D01*
X1155740Y232400D01*
X1152640D01*
G01X1090950Y260500D02*
Y273000D01*
X1094670D01*
X1095910Y272375D01*
X1096840Y270917D01*
X1097150Y269250D01*
X1096840Y267583D01*
X1096065Y266333D01*
X1094670Y265708D01*
X1090950D01*
G01X1103350Y273000D02*
Y260500D01*
X1109550D01*
G01X1114975D02*
X1118850Y273000D01*
X1122725Y260500D01*
G01X1121330Y264875D02*
X1116370D01*
G01X1131250Y273000D02*
Y260500D01*
G01X1127685Y273000D02*
X1134815D01*
G01X1146750Y260500D02*
X1140550D01*
Y273000D01*
X1146750D01*
G01X1144270Y266958D02*
X1140550D01*
G01X1152640Y260500D02*
Y273000D01*
X1155740D01*
X1156980Y272375D01*
X1157910Y271542D01*
X1158685Y270292D01*
X1159305Y268833D01*
X1159460Y266750D01*
X1159305Y264667D01*
X1158685Y263208D01*
X1157910Y261958D01*
X1156980Y261125D01*
X1155740Y260500D01*
X1152640D01*
G01X1090950Y290150D02*
Y302650D01*
X1094670D01*
X1095910Y302025D01*
X1096840Y300567D01*
X1097150Y298900D01*
X1096840Y297233D01*
X1096065Y295983D01*
X1094670Y295358D01*
X1090950D01*
G01X1103350Y302650D02*
Y290150D01*
X1109550D01*
G01X1114975D02*
X1118850Y302650D01*
X1122725Y290150D01*
G01X1121330Y294525D02*
X1116370D01*
G01X1131250Y302650D02*
Y290150D01*
G01X1127685Y302650D02*
X1134815D01*
G01X1146750Y290150D02*
X1140550D01*
Y302650D01*
X1146750D01*
G01X1144270Y296608D02*
X1140550D01*
G01X1152640Y290150D02*
Y302650D01*
X1155740D01*
X1156980Y302025D01*
X1157910Y301192D01*
X1158685Y299942D01*
X1159305Y298483D01*
X1159460Y296400D01*
X1159305Y294317D01*
X1158685Y292858D01*
X1157910Y291608D01*
X1156980Y290775D01*
X1155740Y290150D01*
X1152640D01*
G01X1188600Y308900D02*
Y56000D01*
G01X1211540Y234900D02*
X1212470Y233441D01*
X1213710Y232608D01*
X1215105Y232400D01*
X1216345Y232608D01*
X1217585Y233650D01*
X1218360Y234900D01*
X1218515Y236150D01*
X1218205Y237608D01*
X1217120Y238650D01*
X1216035Y239067D01*
X1214640D01*
G01X1216035D02*
X1216965Y239692D01*
X1217740Y240733D01*
X1218050Y241983D01*
X1217740Y243233D01*
X1216965Y244275D01*
X1215570Y244900D01*
X1214175Y244692D01*
X1212780Y243858D01*
G01X1227350Y232400D02*
Y244900D01*
X1225490Y242400D01*
G01Y232400D02*
X1229210D01*
G01X1241610D02*
Y244900D01*
X1235875Y235942D01*
X1243625D01*
G01X1214950Y260500D02*
Y273000D01*
X1213090Y270500D01*
G01Y260500D02*
X1216810D01*
G01X1223940Y262375D02*
X1224870Y261333D01*
X1225955Y260708D01*
X1227350Y260500D01*
X1228745Y260917D01*
X1229830Y261750D01*
X1230605Y263208D01*
X1230760Y264875D01*
X1230450Y266542D01*
X1229675Y267583D01*
X1228590Y268417D01*
X1227505Y268625D01*
X1226420Y268417D01*
X1225025Y267583D01*
X1225490Y273000D01*
X1229675D01*
G01X1236805Y270917D02*
X1237735Y272166D01*
X1238820Y272792D01*
X1240060Y273000D01*
X1241610Y272583D01*
X1242695Y271542D01*
X1243005Y270292D01*
X1242850Y269041D01*
X1242230Y268000D01*
X1239130Y265917D01*
X1237735Y264458D01*
X1236805Y262375D01*
X1236495Y260500D01*
X1243005D01*
G01X1214950Y290150D02*
X1213710Y290358D01*
X1212625Y291191D01*
X1211695Y292442D01*
X1211075Y293900D01*
X1210765Y295567D01*
Y297233D01*
X1211075Y298900D01*
X1211695Y300358D01*
X1212625Y301608D01*
X1213710Y302442D01*
X1214950Y302650D01*
X1216190Y302442D01*
X1217275Y301608D01*
X1218205Y300358D01*
X1218825Y298900D01*
X1219135Y297233D01*
Y295567D01*
X1218825Y293900D01*
X1218205Y292442D01*
X1217275Y291191D01*
X1216190Y290358D01*
X1214950Y290150D01*
G01X1216190Y293483D02*
X1218050Y290150D01*
G01X1227350Y302650D02*
Y290150D01*
G01X1223785Y302650D02*
X1230915D01*
G01X1239750Y290150D02*
Y295775D01*
X1236650Y302650D01*
G01X1242850D02*
X1239750Y295775D01*
G01X1227040Y63800D02*
X1227350Y66508D01*
X1227815Y68800D01*
X1228435Y70883D01*
X1229210Y73175D01*
X1230450Y76300D01*
X1224250D01*
G01X1227350Y91900D02*
Y104400D01*
X1225490Y101900D01*
G01Y91900D02*
X1229210D01*
G01X1223940Y122500D02*
X1224870Y121041D01*
X1226110Y120208D01*
X1227505Y120000D01*
X1228745Y120208D01*
X1229985Y121250D01*
X1230760Y122500D01*
X1230915Y123750D01*
X1230605Y125208D01*
X1229520Y126250D01*
X1228435Y126667D01*
X1227040D01*
G01X1228435D02*
X1229365Y127292D01*
X1230140Y128333D01*
X1230450Y129583D01*
X1230140Y130833D01*
X1229365Y131875D01*
X1227970Y132500D01*
X1226575Y132292D01*
X1225180Y131458D01*
G01X1224405Y158517D02*
X1225335Y159766D01*
X1226420Y160392D01*
X1227660Y160600D01*
X1229210Y160183D01*
X1230295Y159142D01*
X1230605Y157892D01*
X1230450Y156641D01*
X1229830Y155600D01*
X1226730Y153517D01*
X1225335Y152058D01*
X1224405Y149975D01*
X1224095Y148100D01*
X1230605D01*
G01X1223940Y178700D02*
X1224870Y177241D01*
X1226110Y176408D01*
X1227505Y176200D01*
X1228745Y176408D01*
X1229985Y177450D01*
X1230760Y178700D01*
X1230915Y179950D01*
X1230605Y181408D01*
X1229520Y182450D01*
X1228435Y182867D01*
X1227040D01*
G01X1228435D02*
X1229365Y183492D01*
X1230140Y184533D01*
X1230450Y185783D01*
X1230140Y187033D01*
X1229365Y188075D01*
X1227970Y188700D01*
X1226575Y188492D01*
X1225180Y187658D01*
G01X1223940Y206800D02*
X1224870Y205341D01*
X1226110Y204508D01*
X1227505Y204300D01*
X1228745Y204508D01*
X1229985Y205550D01*
X1230760Y206800D01*
X1230915Y208050D01*
X1230605Y209508D01*
X1229520Y210550D01*
X1228435Y210967D01*
X1227040D01*
G01X1228435D02*
X1229365Y211592D01*
X1230140Y212633D01*
X1230450Y213883D01*
X1230140Y215133D01*
X1229365Y216175D01*
X1227970Y216800D01*
X1226575Y216592D01*
X1225180Y215758D01*
G01X349409Y-9468D02*
Y23347D01*
X321063D01*
G02X319094Y25315I0J1969D01*
G01Y42048D01*
G02X321063Y44016I1969J-1D01*
G01X326181D01*
G03X328149Y45985I0J1968D01*
G01Y171299D01*
G03X326181Y173268I-1968J1D01*
G01X321063D01*
G02X319094Y175236I0J1969D01*
G01Y191969D01*
G01D02*
G02X321063Y193937I1969J-1D01*
G01X349409D01*
Y226752D01*
G01X338081Y117042D02*
X338414Y116509D01*
X338614Y115909D01*
Y115375D01*
X338414Y114842D01*
X338081Y114442D01*
X337614Y114242D01*
X337147Y114375D01*
X336747Y114709D01*
X336481Y115309D01*
X336347Y116109D01*
X336081Y116575D01*
X335614Y116775D01*
X335147Y116642D01*
X334814Y116309D01*
X334614Y115842D01*
Y115375D01*
X334747Y114909D01*
X335081Y114509D01*
G01X338614Y111042D02*
X334614D01*
G01X335947Y106442D02*
X338614D01*
G01X334881D02*
X334814Y106575D01*
X334681D01*
X334614Y106442D01*
X334681Y106309D01*
X334814D01*
X334881Y106442D01*
G01X334614Y101842D02*
X338614D01*
G01X335947Y102775D02*
Y100909D01*
G01X337614Y108642D02*
X328614D01*
X331614Y105642D01*
Y111642D01*
X328614Y108642D01*
M02*
